(kicad_sch (version 20230121) (generator eeschema)

  (paper "A3")

  (title_block
    (title "Kria K26 Devboard")
    (date "2024-03-26")
    (rev "1.2.5")
    (comment 1 "www.antmicro.com")
    (comment 2 "Antmicro Ltd.")
  )

  (junction (at 217.805 116.205) (diameter 0) (color 0 0 0 0)
  )
  (junction (at 236.22 208.915) (diameter 0) (color 0 0 0 0)
  )
  (junction (at 285.115 191.135) (diameter 0) (color 0 0 0 0)
  )
  (junction (at 239.395 191.135) (diameter 0) (color 0 0 0 0)
  )
  (junction (at 208.28 116.205) (diameter 0) (color 0 0 0 0)
  )
  (junction (at 209.55 92.075) (diameter 0) (color 0 0 0 0)
  )
  (junction (at 184.15 126.365) (diameter 0) (color 0 0 0 0)
  )
  (junction (at 125.73 119.38) (diameter 0) (color 0 0 0 0)
  )
  (junction (at 221.615 118.745) (diameter 0) (color 0 0 0 0)
  )
  (junction (at 210.185 118.745) (diameter 0) (color 0 0 0 0)
  )
  (junction (at 285.115 188.595) (diameter 0) (color 0 0 0 0)
  )
  (junction (at 219.71 106.045) (diameter 0) (color 0 0 0 0)
  )
  (junction (at 244.475 208.915) (diameter 0) (color 0 0 0 0)
  )
  (junction (at 125.73 114.3) (diameter 0) (color 0 0 0 0)
  )

  (no_connect (at 245.745 168.275))
  (no_connect (at 245.745 170.815))
  (no_connect (at 245.745 175.895))
  (no_connect (at 245.745 178.435))

  (bus_entry (at 112.395 124.46) (size 2.54 2.54)
    (stroke (width 0) (type default))
  )
  (bus_entry (at 112.395 119.38) (size 2.54 2.54)
    (stroke (width 0) (type default))
  )
  (bus_entry (at 112.395 121.92) (size 2.54 2.54)
    (stroke (width 0) (type default))
  )
  (bus_entry (at 112.395 127) (size 2.54 2.54)
    (stroke (width 0) (type default))
  )

  (wire (pts (xy 217.17 153.67) (xy 220.98 153.67))
    (stroke (width 0) (type default))
  )
  (wire (pts (xy 209.55 92.075) (xy 219.71 92.075))
    (stroke (width 0) (type default))
  )
  (wire (pts (xy 127 84.455) (xy 129.54 84.455))
    (stroke (width 0) (type default))
  )
  (wire (pts (xy 182.245 113.665) (xy 186.055 113.665))
    (stroke (width 0) (type default))
  )
  (wire (pts (xy 146.685 121.92) (xy 161.925 121.92))
    (stroke (width 0) (type default))
  )
  (wire (pts (xy 233.045 114.935) (xy 236.22 114.935))
    (stroke (width 0) (type default))
  )
  (wire (pts (xy 206.375 116.205) (xy 208.28 116.205))
    (stroke (width 0) (type default))
  )
  (wire (pts (xy 219.71 106.045) (xy 217.805 106.045))
    (stroke (width 0) (type default))
  )
  (wire (pts (xy 125.73 119.38) (xy 127.635 119.38))
    (stroke (width 0) (type default))
  )
  (wire (pts (xy 205.74 150.495) (xy 208.28 150.495))
    (stroke (width 0) (type default))
  )
  (wire (pts (xy 234.95 93.345) (xy 247.65 93.345))
    (stroke (width 0) (type default))
  )
  (wire (pts (xy 236.22 212.09) (xy 236.22 208.915))
    (stroke (width 0) (type default))
  )
  (wire (pts (xy 221.615 113.03) (xy 221.615 118.745))
    (stroke (width 0) (type default))
  )
  (wire (pts (xy 146.685 129.54) (xy 161.925 129.54))
    (stroke (width 0) (type default))
  )
  (bus (pts (xy 112.395 124.46) (xy 112.395 127))
    (stroke (width 0) (type default))
  )

  (wire (pts (xy 162.56 208.915) (xy 162.56 207.645))
    (stroke (width 0) (type default))
  )
  (wire (pts (xy 208.28 116.205) (xy 217.805 116.205))
    (stroke (width 0) (type default))
  )
  (wire (pts (xy 127.635 121.92) (xy 114.935 121.92))
    (stroke (width 0) (type default))
  )
  (wire (pts (xy 146.685 109.22) (xy 149.86 109.22))
    (stroke (width 0) (type default))
  )
  (wire (pts (xy 127.635 114.3) (xy 125.73 114.3))
    (stroke (width 0) (type default))
  )
  (wire (pts (xy 145.415 202.565) (xy 163.83 202.565))
    (stroke (width 0) (type default))
  )
  (wire (pts (xy 258.445 113.665) (xy 257.175 113.665))
    (stroke (width 0) (type default))
  )
  (wire (pts (xy 244.475 116.205) (xy 244.475 114.935))
    (stroke (width 0) (type default))
  )
  (wire (pts (xy 210.185 118.745) (xy 210.185 125.095))
    (stroke (width 0) (type default))
  )
  (wire (pts (xy 146.685 124.46) (xy 161.925 124.46))
    (stroke (width 0) (type default))
  )
  (wire (pts (xy 257.175 113.665) (xy 257.175 120.015))
    (stroke (width 0) (type default))
  )
  (wire (pts (xy 285.115 186.055) (xy 285.115 188.595))
    (stroke (width 0) (type default))
  )
  (wire (pts (xy 219.71 92.075) (xy 219.71 106.045))
    (stroke (width 0) (type default))
  )
  (wire (pts (xy 186.055 126.365) (xy 184.15 126.365))
    (stroke (width 0) (type default))
  )
  (wire (pts (xy 285.115 188.595) (xy 285.115 191.135))
    (stroke (width 0) (type default))
  )
  (wire (pts (xy 145.415 197.485) (xy 163.83 197.485))
    (stroke (width 0) (type default))
  )
  (wire (pts (xy 217.805 116.205) (xy 233.045 116.205))
    (stroke (width 0) (type default))
  )
  (wire (pts (xy 245.745 186.055) (xy 227.33 186.055))
    (stroke (width 0) (type default))
  )
  (wire (pts (xy 123.825 116.84) (xy 127.635 116.84))
    (stroke (width 0) (type default))
  )
  (wire (pts (xy 184.15 130.175) (xy 186.055 130.175))
    (stroke (width 0) (type default))
  )
  (wire (pts (xy 245.745 191.135) (xy 239.395 191.135))
    (stroke (width 0) (type default))
  )
  (wire (pts (xy 125.73 114.3) (xy 125.73 119.38))
    (stroke (width 0) (type default))
  )
  (wire (pts (xy 220.98 167.005) (xy 217.17 167.005))
    (stroke (width 0) (type default))
  )
  (wire (pts (xy 241.3 160.655) (xy 245.745 160.655))
    (stroke (width 0) (type default))
  )
  (wire (pts (xy 125.73 119.38) (xy 125.73 130.81))
    (stroke (width 0) (type default))
  )
  (wire (pts (xy 224.155 208.915) (xy 222.25 208.915))
    (stroke (width 0) (type default))
  )
  (wire (pts (xy 285.115 191.135) (xy 285.115 197.485))
    (stroke (width 0) (type default))
  )
  (wire (pts (xy 221.615 106.045) (xy 219.71 106.045))
    (stroke (width 0) (type default))
  )
  (wire (pts (xy 281.305 191.135) (xy 285.115 191.135))
    (stroke (width 0) (type default))
  )
  (wire (pts (xy 231.775 208.915) (xy 236.22 208.915))
    (stroke (width 0) (type default))
  )
  (wire (pts (xy 239.395 191.135) (xy 239.395 193.675))
    (stroke (width 0) (type default))
  )
  (wire (pts (xy 247.65 95.885) (xy 247.65 97.79))
    (stroke (width 0) (type default))
  )
  (wire (pts (xy 271.145 193.675) (xy 273.05 193.675))
    (stroke (width 0) (type default))
  )
  (wire (pts (xy 236.22 208.915) (xy 244.475 208.915))
    (stroke (width 0) (type default))
  )
  (wire (pts (xy 146.685 127) (xy 161.925 127))
    (stroke (width 0) (type default))
  )
  (bus (pts (xy 111.125 118.11) (xy 112.395 118.11))
    (stroke (width 0) (type default))
  )

  (wire (pts (xy 208.28 163.195) (xy 208.28 161.925))
    (stroke (width 0) (type default))
  )
  (wire (pts (xy 184.15 120.015) (xy 186.055 120.015))
    (stroke (width 0) (type default))
  )
  (wire (pts (xy 241.3 155.575) (xy 241.3 153.035))
    (stroke (width 0) (type default))
  )
  (wire (pts (xy 234.95 95.885) (xy 247.65 95.885))
    (stroke (width 0) (type default))
  )
  (wire (pts (xy 184.15 130.175) (xy 184.15 132.08))
    (stroke (width 0) (type default))
  )
  (wire (pts (xy 162.56 207.645) (xy 163.83 207.645))
    (stroke (width 0) (type default))
  )
  (wire (pts (xy 205.74 165.735) (xy 208.28 165.735))
    (stroke (width 0) (type default))
  )
  (wire (pts (xy 276.225 186.055) (xy 271.145 186.055))
    (stroke (width 0) (type default))
  )
  (wire (pts (xy 217.805 106.045) (xy 217.805 107.95))
    (stroke (width 0) (type default))
  )
  (wire (pts (xy 244.475 196.215) (xy 244.475 208.915))
    (stroke (width 0) (type default))
  )
  (wire (pts (xy 205.74 163.195) (xy 208.28 163.195))
    (stroke (width 0) (type default))
  )
  (wire (pts (xy 186.055 123.825) (xy 173.355 123.825))
    (stroke (width 0) (type default))
  )
  (wire (pts (xy 145.415 200.025) (xy 163.83 200.025))
    (stroke (width 0) (type default))
  )
  (wire (pts (xy 148.59 111.76) (xy 148.59 113.665))
    (stroke (width 0) (type default))
  )
  (wire (pts (xy 244.475 118.745) (xy 258.445 118.745))
    (stroke (width 0) (type default))
  )
  (wire (pts (xy 220.98 153.67) (xy 220.98 153.035))
    (stroke (width 0) (type default))
  )
  (wire (pts (xy 241.3 120.015) (xy 244.475 120.015))
    (stroke (width 0) (type default))
  )
  (wire (pts (xy 114.935 127) (xy 127.635 127))
    (stroke (width 0) (type default))
  )
  (wire (pts (xy 114.935 129.54) (xy 127.635 129.54))
    (stroke (width 0) (type default))
  )
  (wire (pts (xy 208.28 153.67) (xy 212.09 153.67))
    (stroke (width 0) (type default))
  )
  (wire (pts (xy 271.145 188.595) (xy 276.225 188.595))
    (stroke (width 0) (type default))
  )
  (wire (pts (xy 244.475 114.935) (xy 241.3 114.935))
    (stroke (width 0) (type default))
  )
  (wire (pts (xy 273.685 118.745) (xy 292.1 118.745))
    (stroke (width 0) (type default))
  )
  (wire (pts (xy 220.98 161.925) (xy 220.98 163.195))
    (stroke (width 0) (type default))
  )
  (wire (pts (xy 245.745 196.215) (xy 244.475 196.215))
    (stroke (width 0) (type default))
  )
  (wire (pts (xy 129.54 84.455) (xy 129.54 86.36))
    (stroke (width 0) (type default))
  )
  (wire (pts (xy 243.84 84.455) (xy 247.65 84.455))
    (stroke (width 0) (type default))
  )
  (wire (pts (xy 239.395 191.135) (xy 227.33 191.135))
    (stroke (width 0) (type default))
  )
  (wire (pts (xy 208.28 149.86) (xy 212.09 149.86))
    (stroke (width 0) (type default))
  )
  (wire (pts (xy 220.98 165.735) (xy 220.98 167.005))
    (stroke (width 0) (type default))
  )
  (wire (pts (xy 285.115 188.595) (xy 281.305 188.595))
    (stroke (width 0) (type default))
  )
  (wire (pts (xy 125.73 114.3) (xy 125.73 111.76))
    (stroke (width 0) (type default))
  )
  (wire (pts (xy 244.475 208.915) (xy 244.475 212.09))
    (stroke (width 0) (type default))
  )
  (wire (pts (xy 242.57 150.495) (xy 242.57 153.035))
    (stroke (width 0) (type default))
  )
  (wire (pts (xy 220.98 150.495) (xy 220.98 149.86))
    (stroke (width 0) (type default))
  )
  (wire (pts (xy 281.305 186.055) (xy 285.115 186.055))
    (stroke (width 0) (type default))
  )
  (wire (pts (xy 206.375 118.745) (xy 210.185 118.745))
    (stroke (width 0) (type default))
  )
  (wire (pts (xy 247.65 86.36) (xy 247.65 84.455))
    (stroke (width 0) (type default))
  )
  (wire (pts (xy 273.05 193.675) (xy 273.05 197.485))
    (stroke (width 0) (type default))
  )
  (wire (pts (xy 274.955 113.665) (xy 274.955 120.015))
    (stroke (width 0) (type default))
  )
  (wire (pts (xy 245.745 183.515) (xy 227.33 183.515))
    (stroke (width 0) (type default))
  )
  (wire (pts (xy 208.28 167.005) (xy 212.09 167.005))
    (stroke (width 0) (type default))
  )
  (wire (pts (xy 244.475 116.205) (xy 258.445 116.205))
    (stroke (width 0) (type default))
  )
  (wire (pts (xy 145.415 205.105) (xy 163.83 205.105))
    (stroke (width 0) (type default))
  )
  (wire (pts (xy 241.3 155.575) (xy 245.745 155.575))
    (stroke (width 0) (type default))
  )
  (wire (pts (xy 244.475 120.015) (xy 244.475 118.745))
    (stroke (width 0) (type default))
  )
  (wire (pts (xy 208.28 150.495) (xy 208.28 149.86))
    (stroke (width 0) (type default))
  )
  (wire (pts (xy 144.78 84.455) (xy 144.78 86.36))
    (stroke (width 0) (type default))
  )
  (wire (pts (xy 142.24 84.455) (xy 144.78 84.455))
    (stroke (width 0) (type default))
  )
  (wire (pts (xy 241.3 163.195) (xy 220.98 163.195))
    (stroke (width 0) (type default))
  )
  (wire (pts (xy 191.135 84.455) (xy 191.135 85.725))
    (stroke (width 0) (type default))
  )
  (wire (pts (xy 220.98 165.735) (xy 242.57 165.735))
    (stroke (width 0) (type default))
  )
  (wire (pts (xy 233.045 120.015) (xy 233.045 118.745))
    (stroke (width 0) (type default))
  )
  (wire (pts (xy 208.28 165.735) (xy 208.28 167.005))
    (stroke (width 0) (type default))
  )
  (wire (pts (xy 208.28 161.925) (xy 212.09 161.925))
    (stroke (width 0) (type default))
  )
  (wire (pts (xy 208.28 116.205) (xy 208.28 122.555))
    (stroke (width 0) (type default))
  )
  (wire (pts (xy 205.74 153.035) (xy 208.28 153.035))
    (stroke (width 0) (type default))
  )
  (wire (pts (xy 242.57 153.035) (xy 245.745 153.035))
    (stroke (width 0) (type default))
  )
  (wire (pts (xy 208.28 153.035) (xy 208.28 153.67))
    (stroke (width 0) (type default))
  )
  (wire (pts (xy 210.185 125.095) (xy 206.375 125.095))
    (stroke (width 0) (type default))
  )
  (wire (pts (xy 148.59 111.76) (xy 146.685 111.76))
    (stroke (width 0) (type default))
  )
  (wire (pts (xy 233.045 120.015) (xy 236.22 120.015))
    (stroke (width 0) (type default))
  )
  (wire (pts (xy 271.145 191.135) (xy 276.225 191.135))
    (stroke (width 0) (type default))
  )
  (wire (pts (xy 220.98 149.86) (xy 217.17 149.86))
    (stroke (width 0) (type default))
  )
  (wire (pts (xy 210.185 118.745) (xy 221.615 118.745))
    (stroke (width 0) (type default))
  )
  (wire (pts (xy 220.98 150.495) (xy 242.57 150.495))
    (stroke (width 0) (type default))
  )
  (wire (pts (xy 221.615 107.95) (xy 221.615 106.045))
    (stroke (width 0) (type default))
  )
  (wire (pts (xy 242.57 163.195) (xy 245.745 163.195))
    (stroke (width 0) (type default))
  )
  (wire (pts (xy 274.955 113.665) (xy 273.685 113.665))
    (stroke (width 0) (type default))
  )
  (wire (pts (xy 114.935 124.46) (xy 127.635 124.46))
    (stroke (width 0) (type default))
  )
  (wire (pts (xy 233.045 114.935) (xy 233.045 116.205))
    (stroke (width 0) (type default))
  )
  (wire (pts (xy 186.055 117.475) (xy 173.355 117.475))
    (stroke (width 0) (type default))
  )
  (wire (pts (xy 242.57 165.735) (xy 242.57 163.195))
    (stroke (width 0) (type default))
  )
  (wire (pts (xy 271.145 196.215) (xy 286.385 196.215))
    (stroke (width 0) (type default))
  )
  (wire (pts (xy 209.55 90.805) (xy 209.55 92.075))
    (stroke (width 0) (type default))
  )
  (wire (pts (xy 273.685 116.205) (xy 292.1 116.205))
    (stroke (width 0) (type default))
  )
  (bus (pts (xy 112.395 121.92) (xy 112.395 124.46))
    (stroke (width 0) (type default))
  )

  (wire (pts (xy 208.28 122.555) (xy 206.375 122.555))
    (stroke (width 0) (type default))
  )
  (wire (pts (xy 184.15 126.365) (xy 184.15 120.015))
    (stroke (width 0) (type default))
  )
  (wire (pts (xy 125.73 111.76) (xy 127.635 111.76))
    (stroke (width 0) (type default))
  )
  (wire (pts (xy 207.645 84.455) (xy 209.55 84.455))
    (stroke (width 0) (type default))
  )
  (wire (pts (xy 221.615 118.745) (xy 233.045 118.745))
    (stroke (width 0) (type default))
  )
  (bus (pts (xy 112.395 119.38) (xy 112.395 121.92))
    (stroke (width 0) (type default))
  )

  (wire (pts (xy 247.65 91.44) (xy 247.65 93.345))
    (stroke (width 0) (type default))
  )
  (wire (pts (xy 191.135 84.455) (xy 187.96 84.455))
    (stroke (width 0) (type default))
  )
  (wire (pts (xy 127.635 109.22) (xy 124.46 109.22))
    (stroke (width 0) (type default))
  )
  (wire (pts (xy 209.55 92.075) (xy 209.55 93.345))
    (stroke (width 0) (type default))
  )
  (wire (pts (xy 217.805 113.03) (xy 217.805 116.205))
    (stroke (width 0) (type default))
  )
  (wire (pts (xy 217.17 161.925) (xy 220.98 161.925))
    (stroke (width 0) (type default))
  )
  (wire (pts (xy 184.15 126.365) (xy 173.355 126.365))
    (stroke (width 0) (type default))
  )
  (wire (pts (xy 220.98 153.035) (xy 241.3 153.035))
    (stroke (width 0) (type default))
  )
  (wire (pts (xy 209.55 84.455) (xy 209.55 85.725))
    (stroke (width 0) (type default))
  )
  (wire (pts (xy 241.3 163.195) (xy 241.3 160.655))
    (stroke (width 0) (type default))
  )
  (bus (pts (xy 112.395 118.11) (xy 112.395 119.38))
    (stroke (width 0) (type default))
  )

  (text "1 A -> B" (at 132.08 133.985 0)
    (effects (font (size 1.27 1.27)) (justify left bottom))
  )
  (text "DisplayPort" (at 184.785 78.105 0)
    (effects (font (size 2.54 2.54) (thickness 0.508) bold) (justify left bottom))
  )
  (text "2 A <- B" (at 132.08 136.525 0)
    (effects (font (size 1.27 1.27)) (justify left bottom))
  )

  (label "DP_AUX_C_P" (at 244.475 116.205 0) (fields_autoplaced)
    (effects (font (size 1.27 1.27)) (justify left bottom))
  )
  (label "DP_OE" (at 161.925 124.46 180) (fields_autoplaced)
    (effects (font (size 1.27 1.27)) (justify right bottom))
  )
  (label "GTR_DP0_M2C_C_N" (at 145.415 205.105 0) (fields_autoplaced)
    (effects (font (size 1.27 1.27)) (justify left bottom))
  )
  (label "DP_AUX_C_TVS_N" (at 292.1 118.745 180) (fields_autoplaced)
    (effects (font (size 1.27 1.27)) (justify right bottom))
  )
  (label "DP_OE" (at 173.355 126.365 0) (fields_autoplaced)
    (effects (font (size 1.27 1.27)) (justify left bottom))
  )
  (label "DP_AUX_C_N" (at 244.475 118.745 0) (fields_autoplaced)
    (effects (font (size 1.27 1.27)) (justify left bottom))
  )
  (label "GTR_DP0_M2C_C_P" (at 222.25 163.195 0) (fields_autoplaced)
    (effects (font (size 1.27 1.27)) (justify left bottom))
  )
  (label "DP_HPD" (at 161.925 129.54 180) (fields_autoplaced)
    (effects (font (size 1.27 1.27)) (justify right bottom))
  )
  (label "MIO27" (at 114.935 121.92 0) (fields_autoplaced)
    (effects (font (size 1.27 1.27)) (justify left bottom))
  )
  (label "GTR_DP1_M2C_C_N" (at 222.25 153.035 0) (fields_autoplaced)
    (effects (font (size 1.27 1.27)) (justify left bottom))
  )
  (label "GTR_DP1_M2C_C_P" (at 145.415 197.485 0) (fields_autoplaced)
    (effects (font (size 1.27 1.27)) (justify left bottom))
  )
  (label "DP_AUX_IN" (at 173.355 123.825 0) (fields_autoplaced)
    (effects (font (size 1.27 1.27)) (justify left bottom))
  )
  (label "GTR_DP0_M2C_C_P" (at 145.415 202.565 0) (fields_autoplaced)
    (effects (font (size 1.27 1.27)) (justify left bottom))
  )
  (label "MIO30" (at 114.935 127 0) (fields_autoplaced)
    (effects (font (size 1.27 1.27)) (justify left bottom))
  )
  (label "GTR_DP1_M2C_C_N" (at 145.415 200.025 0) (fields_autoplaced)
    (effects (font (size 1.27 1.27)) (justify left bottom))
  )
  (label "DP_HPD" (at 227.33 191.135 0) (fields_autoplaced)
    (effects (font (size 1.27 1.27)) (justify left bottom))
  )
  (label "DP_AUX_OUT" (at 161.925 121.92 180) (fields_autoplaced)
    (effects (font (size 1.27 1.27)) (justify right bottom))
  )
  (label "DP_AUX_C_TVS_N" (at 227.33 186.055 0) (fields_autoplaced)
    (effects (font (size 1.27 1.27)) (justify left bottom))
  )
  (label "DP_AUX_C_P" (at 234.95 95.885 0) (fields_autoplaced)
    (effects (font (size 1.27 1.27)) (justify left bottom))
  )
  (label "GTR_DP1_M2C_C_P" (at 222.25 150.495 0) (fields_autoplaced)
    (effects (font (size 1.27 1.27)) (justify left bottom))
  )
  (label "DP_AUX_C_TVS_P" (at 227.33 183.515 0) (fields_autoplaced)
    (effects (font (size 1.27 1.27)) (justify left bottom))
  )
  (label "MIO28" (at 114.935 129.54 0) (fields_autoplaced)
    (effects (font (size 1.27 1.27)) (justify left bottom))
  )
  (label "MIO29" (at 114.935 124.46 0) (fields_autoplaced)
    (effects (font (size 1.27 1.27)) (justify left bottom))
  )
  (label "DP_AUX_P" (at 232.41 116.205 180) (fields_autoplaced)
    (effects (font (size 1.27 1.27)) (justify right bottom))
  )
  (label "DP_AUX_N" (at 232.41 118.745 180) (fields_autoplaced)
    (effects (font (size 1.27 1.27)) (justify right bottom))
  )
  (label "DP_AUX_IN" (at 161.925 127 180) (fields_autoplaced)
    (effects (font (size 1.27 1.27)) (justify right bottom))
  )
  (label "DP_AUX_OUT" (at 173.355 117.475 0) (fields_autoplaced)
    (effects (font (size 1.27 1.27)) (justify left bottom))
  )
  (label "DP_AUX_C_TVS_P" (at 292.1 116.205 180) (fields_autoplaced)
    (effects (font (size 1.27 1.27)) (justify right bottom))
  )
  (label "DP_AUX_C_N" (at 234.95 93.345 0) (fields_autoplaced)
    (effects (font (size 1.27 1.27)) (justify left bottom))
  )
  (label "GTR_DP0_M2C_C_N" (at 222.25 165.735 0) (fields_autoplaced)
    (effects (font (size 1.27 1.27)) (justify left bottom))
  )

  (global_label "PS_1V8" (shape input) (at 124.46 109.22 180) (fields_autoplaced)
    (effects (font (size 1.27 1.27)) (justify right))
    (property "Intersheetrefs" "${INTERSHEET_REFS}" (at 44.45 163.83 0)
      (effects (font (size 1.27 1.27)) hide)
    )
  )
  (global_label "PS_3V3" (shape input) (at 222.25 208.915 180) (fields_autoplaced)
    (effects (font (size 1.27 1.27)) (justify right))
    (property "Intersheetrefs" "${INTERSHEET_REFS}" (at 491.49 90.805 0)
      (effects (font (size 1.27 1.27)) (justify left) hide)
    )
  )
  (global_label "PS_1V8" (shape input) (at 123.825 116.84 180) (fields_autoplaced)
    (effects (font (size 1.27 1.27)) (justify right))
    (property "Intersheetrefs" "${INTERSHEET_REFS}" (at 80.645 11.43 0)
      (effects (font (size 1.27 1.27)) hide)
    )
  )
  (global_label "PS_3V3" (shape input) (at 182.245 113.665 180) (fields_autoplaced)
    (effects (font (size 1.27 1.27)) (justify right))
    (property "Intersheetrefs" "${INTERSHEET_REFS}" (at 102.235 219.075 0)
      (effects (font (size 1.27 1.27)) hide)
    )
  )
  (global_label "PS_3V3" (shape input) (at 187.96 84.455 180) (fields_autoplaced)
    (effects (font (size 1.27 1.27)) (justify right))
    (property "Intersheetrefs" "${INTERSHEET_REFS}" (at 107.95 189.865 0)
      (effects (font (size 1.27 1.27)) hide)
    )
  )
  (global_label "PS_3V3" (shape input) (at 149.86 109.22 0) (fields_autoplaced)
    (effects (font (size 1.27 1.27)) (justify left))
    (property "Intersheetrefs" "${INTERSHEET_REFS}" (at 229.87 49.53 0)
      (effects (font (size 1.27 1.27)) hide)
    )
  )
  (global_label "PS_1V8" (shape input) (at 127 84.455 180) (fields_autoplaced)
    (effects (font (size 1.27 1.27)) (justify right))
    (property "Intersheetrefs" "${INTERSHEET_REFS}" (at 46.99 139.065 0)
      (effects (font (size 1.27 1.27)) hide)
    )
  )
  (global_label "SH_UP" (shape input) (at 286.385 196.215 0) (fields_autoplaced)
    (effects (font (size 1.27 1.27)) (justify left))
    (property "Intersheetrefs" "${INTERSHEET_REFS}" (at 164.465 408.305 0)
      (effects (font (size 1.27 1.27)) hide)
    )
  )
  (global_label "PS_3V3" (shape input) (at 207.645 84.455 180) (fields_autoplaced)
    (effects (font (size 1.27 1.27)) (justify right))
    (property "Intersheetrefs" "${INTERSHEET_REFS}" (at 136.525 225.425 0)
      (effects (font (size 1.27 1.27)) hide)
    )
  )
  (global_label "PS_3V3" (shape input) (at 142.24 84.455 180) (fields_autoplaced)
    (effects (font (size 1.27 1.27)) (justify right))
    (property "Intersheetrefs" "${INTERSHEET_REFS}" (at 62.23 144.145 0)
      (effects (font (size 1.27 1.27)) hide)
    )
  )
  (global_label "PS_3V3" (shape input) (at 243.84 84.455 180) (fields_autoplaced)
    (effects (font (size 1.27 1.27)) (justify right))
    (property "Intersheetrefs" "${INTERSHEET_REFS}" (at 115.57 263.525 0)
      (effects (font (size 1.27 1.27)) hide)
    )
  )

  (hierarchical_label "GTR_DP1_M2C_N" (shape input) (at 205.74 153.035 180) (fields_autoplaced)
    (effects (font (size 1.27 1.27)) (justify right))
  )
  (hierarchical_label "GTR_DP0_M2C_P" (shape input) (at 205.74 163.195 180) (fields_autoplaced)
    (effects (font (size 1.27 1.27)) (justify right))
  )
  (hierarchical_label "GTR_DP1_M2C_P" (shape input) (at 205.74 150.495 180) (fields_autoplaced)
    (effects (font (size 1.27 1.27)) (justify right))
  )
  (hierarchical_label "MIO[27..30]" (shape input) (at 111.125 118.11 180) (fields_autoplaced)
    (effects (font (size 1.27 1.27)) (justify right))
  )
  (hierarchical_label "GTR_DP0_M2C_N" (shape input) (at 205.74 165.735 180) (fields_autoplaced)
    (effects (font (size 1.27 1.27)) (justify right))
  )

  (symbol (lib_id "kria-k26-devboard:824012823") (at 273.685 118.745 180) (unit 1)
    (in_bom yes) (on_board yes) (dnp no) (fields_autoplaced)
    (property "Reference" "U4" (at 266.0015 106.045 0)
      (effects (font (size 1.27 1.27)))
    )
    (property "Value" "824012823" (at 266.0015 108.585 0)
      (effects (font (size 1.27 1.27) (thickness 0.15)))
    )
    (property "Footprint" "kria-k26-devboard-footprints:DFN1210-6" (at 243.205 108.585 0)
      (effects (font (size 1.27 1.27) (thickness 0.15)) (justify left bottom) hide)
    )
    (property "Datasheet" "https://www.we-online.com/catalog/datasheet/824012823.pdf" (at 243.205 106.045 0)
      (effects (font (size 1.27 1.27) (thickness 0.15)) (justify left bottom) hide)
    )
    (property "MPN" "824012823" (at 243.205 103.505 0)
      (effects (font (size 1.27 1.27) (thickness 0.15)) (justify left bottom) hide)
    )
    (property "Manufacturer" "Würth Elektronik" (at 243.205 100.965 0)
      (effects (font (size 1.27 1.27) (thickness 0.15)) (justify left bottom) hide)
    )
    (property "Author" "Antmicro" (at 243.205 98.425 0)
      (effects (font (size 1.27 1.27) (thickness 0.15)) (justify left bottom) hide)
    )
    (property "License" "Apache-2.0" (at 243.205 95.885 0)
      (effects (font (size 1.27 1.27) (thickness 0.15)) (justify left bottom) hide)
    )
    (pin "1")
    (pin "2")
    (pin "3")
    (pin "4")
    (pin "5")
    (pin "6")
    (instances
      (project "kria-k26-devboard"
        (path ""
          (reference "U4") (unit 1)
        )
      )
    )
  )

  (symbol (lib_id "kria-k26-devboard:GND") (at 274.955 120.015 0) (unit 1)
    (in_bom yes) (on_board yes) (dnp no) (fields_autoplaced)
    (property "Reference" "#PWR014" (at 274.955 126.365 0)
      (effects (font (size 1.27 1.27)) hide)
    )
    (property "Value" "GND" (at 274.955 125.095 0)
      (effects (font (size 1.27 1.27)))
    )
    (property "Footprint" "" (at 283.845 127.635 0)
      (effects (font (size 1.27 1.27) (thickness 0.15)) (justify left bottom) hide)
    )
    (property "Datasheet" "" (at 283.845 132.715 0)
      (effects (font (size 1.27 1.27) (thickness 0.15)) (justify left bottom) hide)
    )
    (property "Author" "Antmicro" (at 283.845 127.635 0)
      (effects (font (size 1.27 1.27) (thickness 0.15)) (justify left bottom) hide)
    )
    (property "License" "Apache-2.0" (at 283.845 130.175 0)
      (effects (font (size 1.27 1.27) (thickness 0.15)) (justify left bottom) hide)
    )
    (pin "1")
    (instances
      (project "kria-k26-devboard"
        (path ""
          (reference "#PWR014") (unit 1)
        )
      )
    )
  )

  (symbol (lib_id "kria-k26-devboard:74AVC4T245_UQFN") (at 127.635 111.76 0) (unit 1)
    (in_bom yes) (on_board yes) (dnp no) (fields_autoplaced)
    (property "Reference" "U1" (at 137.16 101.6 0)
      (effects (font (size 1.27 1.27)))
    )
    (property "Value" "74AVC4T245_UQFN" (at 137.16 104.14 0)
      (effects (font (size 1.27 1.27) (thickness 0.15)))
    )
    (property "Footprint" "kria-k26-devboard-footprints:UQFN-16-1.8x2.6mm_P0.4mm_Texas_RSV0016A" (at 165.735 119.38 0)
      (effects (font (size 1.27 1.27) (thickness 0.15)) (justify left bottom) hide)
    )
    (property "Datasheet" "https://www.ti.com/lit/ds/symlink/sn74avc4t245.pdf" (at 165.735 121.92 0)
      (effects (font (size 1.27 1.27) (thickness 0.15)) (justify left bottom) hide)
    )
    (property "MPN" "74AVC4T245RSVRG4" (at 165.735 124.46 0)
      (effects (font (size 1.27 1.27) (thickness 0.15)) (justify left bottom) hide)
    )
    (property "Manufacturer" "Texas Instruments" (at 165.735 127 0)
      (effects (font (size 1.27 1.27) (thickness 0.15)) (justify left bottom) hide)
    )
    (property "Author" "Antmicro" (at 165.735 129.54 0)
      (effects (font (size 1.27 1.27) (thickness 0.15)) (justify left bottom) hide)
    )
    (property "License" "Apache-2.0" (at 165.735 132.08 0)
      (effects (font (size 1.27 1.27) (thickness 0.15)) (justify left bottom) hide)
    )
    (pin "1")
    (pin "10")
    (pin "11")
    (pin "12")
    (pin "13")
    (pin "14")
    (pin "15")
    (pin "16")
    (pin "2")
    (pin "3")
    (pin "4")
    (pin "5")
    (pin "6")
    (pin "7")
    (pin "8")
    (pin "9")
    (instances
      (project "kria-k26-devboard"
        (path ""
          (reference "U1") (unit 1)
        )
      )
    )
  )

  (symbol (lib_id "kria-k26-devboard:DisplayPort_Molex_472720001") (at 245.745 153.035 0) (unit 1)
    (in_bom yes) (on_board yes) (dnp no)
    (property "Reference" "J1" (at 258.445 146.05 0)
      (effects (font (size 1.524 1.524)))
    )
    (property "Value" "DisplayPort_Molex_472720001" (at 258.5085 147.32 0)
      (effects (font (size 1.27 1.27) (thickness 0.15)) hide)
    )
    (property "Footprint" "kria-k26-devboard-footprints:DisplayPort_Receptacle_Molex_472720001" (at 286.385 160.655 0)
      (effects (font (size 1.27 1.27) (thickness 0.15)) (justify left bottom) hide)
    )
    (property "Datasheet" "https://www.molex.com/en-us/products/part-detail/472720001" (at 286.385 163.195 0)
      (effects (font (size 1.27 1.27) (thickness 0.15)) (justify left bottom) hide)
    )
    (property "MPN" "472720001" (at 258.445 148.59 0)
      (effects (font (size 1.27 1.27) (thickness 0.15)))
    )
    (property "Manufacturer" "Molex" (at 286.385 168.275 0)
      (effects (font (size 1.27 1.27) (thickness 0.15)) (justify left bottom) hide)
    )
    (property "Author" "Antmicro" (at 286.385 170.815 0)
      (effects (font (size 1.27 1.27) (thickness 0.15)) (justify left bottom) hide)
    )
    (property "License" "Apache-2.0" (at 286.385 173.355 0)
      (effects (font (size 1.27 1.27) (thickness 0.15)) (justify left bottom) hide)
    )
    (pin "1")
    (pin "10")
    (pin "11")
    (pin "12")
    (pin "13")
    (pin "14")
    (pin "15")
    (pin "16")
    (pin "17")
    (pin "18")
    (pin "19")
    (pin "2")
    (pin "20")
    (pin "3")
    (pin "4")
    (pin "5")
    (pin "6")
    (pin "7")
    (pin "8")
    (pin "9")
    (pin "SH")
    (instances
      (project "kria-k26-devboard"
        (path ""
          (reference "J1") (unit 1)
        )
      )
    )
  )

  (symbol (lib_id "kria-k26-devboard:FIN1019MTC") (at 186.055 113.665 0) (unit 1)
    (in_bom yes) (on_board yes) (dnp no) (fields_autoplaced)
    (property "Reference" "U2" (at 196.215 106.045 0)
      (effects (font (size 1.27 1.27)))
    )
    (property "Value" "FIN1019MTC" (at 196.215 108.585 0)
      (effects (font (size 1.27 1.27) (thickness 0.15)))
    )
    (property "Footprint" "kria-k26-devboard-footprints:TSSOP-14_4.4x5mm_P0.65mm" (at 241.935 128.905 0)
      (effects (font (size 1.27 1.27) (thickness 0.15)) (justify left bottom) hide)
    )
    (property "Datasheet" "http://www.onsemi.com/pub/Collateral/FIN1019-D.pdf" (at 241.935 131.445 0)
      (effects (font (size 1.27 1.27) (thickness 0.15)) (justify left bottom) hide)
    )
    (property "Manufacturer" "ON Semiconductor" (at 241.935 133.985 0)
      (effects (font (size 1.27 1.27) (thickness 0.15)) (justify left bottom) hide)
    )
    (property "MPN" "FIN1019MTCX" (at 241.935 136.525 0)
      (effects (font (size 1.27 1.27) (thickness 0.15)) (justify left bottom) hide)
    )
    (property "Author" "Antmicro" (at 241.935 139.065 0)
      (effects (font (size 1.27 1.27) (thickness 0.15)) (justify left bottom) hide)
    )
    (property "License" "Apache-2.0" (at 241.935 141.605 0)
      (effects (font (size 1.27 1.27) (thickness 0.15)) (justify left bottom) hide)
    )
    (pin "1")
    (pin "10")
    (pin "11")
    (pin "12")
    (pin "13")
    (pin "14")
    (pin "2")
    (pin "3")
    (pin "4")
    (pin "5")
    (pin "6")
    (pin "7")
    (pin "8")
    (pin "9")
    (instances
      (project "kria-k26-devboard"
        (path ""
          (reference "U2") (unit 1)
        )
      )
    )
  )

  (symbol (lib_id "kria-k26-devboard:GND") (at 148.59 113.665 0) (unit 1)
    (in_bom yes) (on_board yes) (dnp no) (fields_autoplaced)
    (property "Reference" "#PWR06" (at 148.59 120.015 0)
      (effects (font (size 1.27 1.27)) hide)
    )
    (property "Value" "GND" (at 148.59 118.11 0)
      (effects (font (size 1.27 1.27)))
    )
    (property "Footprint" "" (at 157.48 121.285 0)
      (effects (font (size 1.27 1.27) (thickness 0.15)) (justify left bottom) hide)
    )
    (property "Datasheet" "" (at 157.48 126.365 0)
      (effects (font (size 1.27 1.27) (thickness 0.15)) (justify left bottom) hide)
    )
    (property "Author" "Antmicro" (at 157.48 121.285 0)
      (effects (font (size 1.27 1.27) (thickness 0.15)) (justify left bottom) hide)
    )
    (property "License" "Apache-2.0" (at 157.48 123.825 0)
      (effects (font (size 1.27 1.27) (thickness 0.15)) (justify left bottom) hide)
    )
    (pin "1")
    (instances
      (project "kria-k26-devboard"
        (path ""
          (reference "#PWR06") (unit 1)
        )
      )
    )
  )

  (symbol (lib_id "kria-k26-devboard:C_100n_0402") (at 129.54 86.36 270) (unit 1)
    (in_bom yes) (on_board yes) (dnp no) (fields_autoplaced)
    (property "Reference" "C3" (at 127 87.6363 90)
      (effects (font (size 1.524 1.524)) (justify right))
    )
    (property "Value" "C_100n_0402" (at 119.38 106.68 0)
      (effects (font (size 1.27 1.27) (thickness 0.15)) (justify left bottom) hide)
    )
    (property "Footprint" "kria-k26-devboard-footprints:C_0402_1005Metric" (at 116.84 106.68 0)
      (effects (font (size 1.27 1.27) (thickness 0.15)) (justify left bottom) hide)
    )
    (property "Datasheet" "https://search.murata.co.jp/Ceramy/image/img/A01X/G101/ENG/GRM155R61H104KE14-01.pdf" (at 114.3 106.68 0)
      (effects (font (size 1.27 1.27) (thickness 0.15)) (justify left bottom) hide)
    )
    (property "Manufacturer" "Murata" (at 109.22 106.68 0)
      (effects (font (size 1.27 1.27) (thickness 0.15)) (justify left bottom) hide)
    )
    (property "MPN" "GRM155R61H104KE14D" (at 111.76 106.68 0)
      (effects (font (size 1.27 1.27) (thickness 0.15)) (justify left bottom) hide)
    )
    (property "Val" "100n" (at 127 90.8112 90)
      (effects (font (size 1.27 1.27) (thickness 0.15)) (justify right))
    )
    (property "License" "Apache-2.0" (at 106.68 106.68 0)
      (effects (font (size 1.27 1.27) (thickness 0.15)) (justify left bottom) hide)
    )
    (property "Author" "Antmicro" (at 104.14 106.68 0)
      (effects (font (size 1.27 1.27) (thickness 0.15)) (justify left bottom) hide)
    )
    (property "Voltage" "50V" (at 101.6 106.68 0)
      (effects (font (size 1.27 1.27)) (justify left bottom) hide)
    )
    (property "Dielectric" "X5R" (at 99.06 106.68 0)
      (effects (font (size 1.27 1.27)) (justify left bottom) hide)
    )
    (pin "1")
    (pin "2")
    (instances
      (project "kria-k26-devboard"
        (path ""
          (reference "C3") (unit 1)
        )
      )
    )
  )

  (symbol (lib_id "kria-k26-devboard:C_100n_0402") (at 144.78 86.36 270) (unit 1)
    (in_bom yes) (on_board yes) (dnp no) (fields_autoplaced)
    (property "Reference" "C4" (at 147.32 87.6363 90)
      (effects (font (size 1.524 1.524)) (justify left))
    )
    (property "Value" "C_100n_0402" (at 134.62 106.68 0)
      (effects (font (size 1.27 1.27) (thickness 0.15)) (justify left bottom) hide)
    )
    (property "Footprint" "kria-k26-devboard-footprints:C_0402_1005Metric" (at 132.08 106.68 0)
      (effects (font (size 1.27 1.27) (thickness 0.15)) (justify left bottom) hide)
    )
    (property "Datasheet" "https://search.murata.co.jp/Ceramy/image/img/A01X/G101/ENG/GRM155R61H104KE14-01.pdf" (at 129.54 106.68 0)
      (effects (font (size 1.27 1.27) (thickness 0.15)) (justify left bottom) hide)
    )
    (property "Manufacturer" "Murata" (at 124.46 106.68 0)
      (effects (font (size 1.27 1.27) (thickness 0.15)) (justify left bottom) hide)
    )
    (property "MPN" "GRM155R61H104KE14D" (at 127 106.68 0)
      (effects (font (size 1.27 1.27) (thickness 0.15)) (justify left bottom) hide)
    )
    (property "Val" "100n" (at 147.32 90.8112 90)
      (effects (font (size 1.27 1.27) (thickness 0.15)) (justify left))
    )
    (property "License" "Apache-2.0" (at 121.92 106.68 0)
      (effects (font (size 1.27 1.27) (thickness 0.15)) (justify left bottom) hide)
    )
    (property "Author" "Antmicro" (at 119.38 106.68 0)
      (effects (font (size 1.27 1.27) (thickness 0.15)) (justify left bottom) hide)
    )
    (property "Voltage" "50V" (at 116.84 106.68 0)
      (effects (font (size 1.27 1.27)) (justify left bottom) hide)
    )
    (property "Dielectric" "X5R" (at 114.3 106.68 0)
      (effects (font (size 1.27 1.27)) (justify left bottom) hide)
    )
    (pin "1")
    (pin "2")
    (instances
      (project "kria-k26-devboard"
        (path ""
          (reference "C4") (unit 1)
        )
      )
    )
  )

  (symbol (lib_id "kria-k26-devboard:GND") (at 144.78 91.44 0) (unit 1)
    (in_bom yes) (on_board yes) (dnp no) (fields_autoplaced)
    (property "Reference" "#PWR07" (at 144.78 97.79 0)
      (effects (font (size 1.27 1.27)) hide)
    )
    (property "Value" "GND" (at 144.78 96.52 0)
      (effects (font (size 1.27 1.27)))
    )
    (property "Footprint" "" (at 153.67 99.06 0)
      (effects (font (size 1.27 1.27) (thickness 0.15)) (justify left bottom) hide)
    )
    (property "Datasheet" "" (at 153.67 104.14 0)
      (effects (font (size 1.27 1.27) (thickness 0.15)) (justify left bottom) hide)
    )
    (property "Author" "Antmicro" (at 153.67 99.06 0)
      (effects (font (size 1.27 1.27) (thickness 0.15)) (justify left bottom) hide)
    )
    (property "License" "Apache-2.0" (at 153.67 101.6 0)
      (effects (font (size 1.27 1.27) (thickness 0.15)) (justify left bottom) hide)
    )
    (pin "1")
    (instances
      (project "kria-k26-devboard"
        (path ""
          (reference "#PWR07") (unit 1)
        )
      )
    )
  )

  (symbol (lib_id "kria-k26-devboard:GND") (at 129.54 91.44 0) (unit 1)
    (in_bom yes) (on_board yes) (dnp no) (fields_autoplaced)
    (property "Reference" "#PWR05" (at 129.54 97.79 0)
      (effects (font (size 1.27 1.27)) hide)
    )
    (property "Value" "GND" (at 129.54 96.52 0)
      (effects (font (size 1.27 1.27)))
    )
    (property "Footprint" "" (at 138.43 99.06 0)
      (effects (font (size 1.27 1.27) (thickness 0.15)) (justify left bottom) hide)
    )
    (property "Datasheet" "" (at 138.43 104.14 0)
      (effects (font (size 1.27 1.27) (thickness 0.15)) (justify left bottom) hide)
    )
    (property "Author" "Antmicro" (at 138.43 99.06 0)
      (effects (font (size 1.27 1.27) (thickness 0.15)) (justify left bottom) hide)
    )
    (property "License" "Apache-2.0" (at 138.43 101.6 0)
      (effects (font (size 1.27 1.27) (thickness 0.15)) (justify left bottom) hide)
    )
    (pin "1")
    (instances
      (project "kria-k26-devboard"
        (path ""
          (reference "#PWR05") (unit 1)
        )
      )
    )
  )

  (symbol (lib_id "kria-k26-devboard:GND") (at 125.73 130.81 0) (unit 1)
    (in_bom yes) (on_board yes) (dnp no) (fields_autoplaced)
    (property "Reference" "#PWR04" (at 125.73 137.16 0)
      (effects (font (size 1.27 1.27)) hide)
    )
    (property "Value" "GND" (at 125.73 135.255 0)
      (effects (font (size 1.27 1.27)))
    )
    (property "Footprint" "" (at 134.62 138.43 0)
      (effects (font (size 1.27 1.27) (thickness 0.15)) (justify left bottom) hide)
    )
    (property "Datasheet" "" (at 134.62 143.51 0)
      (effects (font (size 1.27 1.27) (thickness 0.15)) (justify left bottom) hide)
    )
    (property "Author" "Antmicro" (at 134.62 138.43 0)
      (effects (font (size 1.27 1.27) (thickness 0.15)) (justify left bottom) hide)
    )
    (property "License" "Apache-2.0" (at 134.62 140.97 0)
      (effects (font (size 1.27 1.27) (thickness 0.15)) (justify left bottom) hide)
    )
    (pin "1")
    (instances
      (project "kria-k26-devboard"
        (path ""
          (reference "#PWR04") (unit 1)
        )
      )
    )
  )

  (symbol (lib_id "kria-k26-devboard:C_100n_0402") (at 191.135 85.725 90) (mirror x) (unit 1)
    (in_bom yes) (on_board yes) (dnp no) (fields_autoplaced)
    (property "Reference" "C5" (at 193.675 87.0013 90)
      (effects (font (size 1.524 1.524)) (justify right))
    )
    (property "Value" "C_100n_0402" (at 201.295 106.045 0)
      (effects (font (size 1.27 1.27) (thickness 0.15)) (justify left bottom) hide)
    )
    (property "Footprint" "kria-k26-devboard-footprints:C_0402_1005Metric" (at 203.835 106.045 0)
      (effects (font (size 1.27 1.27) (thickness 0.15)) (justify left bottom) hide)
    )
    (property "Datasheet" "https://search.murata.co.jp/Ceramy/image/img/A01X/G101/ENG/GRM155R61H104KE14-01.pdf" (at 206.375 106.045 0)
      (effects (font (size 1.27 1.27) (thickness 0.15)) (justify left bottom) hide)
    )
    (property "Manufacturer" "Murata" (at 211.455 106.045 0)
      (effects (font (size 1.27 1.27) (thickness 0.15)) (justify left bottom) hide)
    )
    (property "MPN" "GRM155R61H104KE14D" (at 208.915 106.045 0)
      (effects (font (size 1.27 1.27) (thickness 0.15)) (justify left bottom) hide)
    )
    (property "Val" "100n" (at 193.675 90.1762 90)
      (effects (font (size 1.27 1.27) (thickness 0.15)) (justify right))
    )
    (property "License" "Apache-2.0" (at 213.995 106.045 0)
      (effects (font (size 1.27 1.27) (thickness 0.15)) (justify left bottom) hide)
    )
    (property "Author" "Antmicro" (at 216.535 106.045 0)
      (effects (font (size 1.27 1.27) (thickness 0.15)) (justify left bottom) hide)
    )
    (property "Voltage" "50V" (at 219.075 106.045 0)
      (effects (font (size 1.27 1.27)) (justify left bottom) hide)
    )
    (property "Dielectric" "X5R" (at 221.615 106.045 0)
      (effects (font (size 1.27 1.27)) (justify left bottom) hide)
    )
    (pin "1")
    (pin "2")
    (instances
      (project "kria-k26-devboard"
        (path ""
          (reference "C5") (unit 1)
        )
      )
    )
  )

  (symbol (lib_id "kria-k26-devboard:GND") (at 191.135 90.805 0) (mirror y) (unit 1)
    (in_bom yes) (on_board yes) (dnp no) (fields_autoplaced)
    (property "Reference" "#PWR08" (at 191.135 97.155 0)
      (effects (font (size 1.27 1.27)) hide)
    )
    (property "Value" "GND" (at 191.135 95.885 0)
      (effects (font (size 1.27 1.27)))
    )
    (property "Footprint" "" (at 182.245 98.425 0)
      (effects (font (size 1.27 1.27) (thickness 0.15)) (justify left bottom) hide)
    )
    (property "Datasheet" "" (at 182.245 103.505 0)
      (effects (font (size 1.27 1.27) (thickness 0.15)) (justify left bottom) hide)
    )
    (property "Author" "Antmicro" (at 182.245 98.425 0)
      (effects (font (size 1.27 1.27) (thickness 0.15)) (justify left bottom) hide)
    )
    (property "License" "Apache-2.0" (at 182.245 100.965 0)
      (effects (font (size 1.27 1.27) (thickness 0.15)) (justify left bottom) hide)
    )
    (pin "1")
    (instances
      (project "kria-k26-devboard"
        (path ""
          (reference "#PWR08") (unit 1)
        )
      )
    )
  )

  (symbol (lib_id "kria-k26-devboard:GND") (at 184.15 132.08 0) (unit 1)
    (in_bom yes) (on_board yes) (dnp no) (fields_autoplaced)
    (property "Reference" "#PWR09" (at 184.15 138.43 0)
      (effects (font (size 1.27 1.27)) hide)
    )
    (property "Value" "GND" (at 184.15 137.16 0)
      (effects (font (size 1.27 1.27)))
    )
    (property "Footprint" "" (at 193.04 139.7 0)
      (effects (font (size 1.27 1.27) (thickness 0.15)) (justify left bottom) hide)
    )
    (property "Datasheet" "" (at 193.04 144.78 0)
      (effects (font (size 1.27 1.27) (thickness 0.15)) (justify left bottom) hide)
    )
    (property "Author" "Antmicro" (at 193.04 139.7 0)
      (effects (font (size 1.27 1.27) (thickness 0.15)) (justify left bottom) hide)
    )
    (property "License" "Apache-2.0" (at 193.04 142.24 0)
      (effects (font (size 1.27 1.27) (thickness 0.15)) (justify left bottom) hide)
    )
    (pin "1")
    (instances
      (project "kria-k26-devboard"
        (path ""
          (reference "#PWR09") (unit 1)
        )
      )
    )
  )

  (symbol (lib_id "kria-k26-devboard:R_49R9_0402") (at 221.615 113.03 90) (unit 1)
    (in_bom yes) (on_board yes) (dnp no) (fields_autoplaced)
    (property "Reference" "R4" (at 224.155 109.22 90)
      (effects (font (size 1.524 1.524)) (justify right))
    )
    (property "Value" "R_49R9_0402" (at 234.315 92.71 0)
      (effects (font (size 1.27 1.27) (thickness 0.15)) (justify left bottom) hide)
    )
    (property "Footprint" "kria-k26-devboard-footprints:R_0402_1005Metric" (at 236.855 92.71 0)
      (effects (font (size 1.27 1.27) (thickness 0.15)) (justify left bottom) hide)
    )
    (property "Datasheet" "https://www.bourns.com/docs/product-datasheets/cr.pdf" (at 239.395 92.71 0)
      (effects (font (size 1.27 1.27) (thickness 0.15)) (justify left bottom) hide)
    )
    (property "Manufacturer" "Bourns" (at 244.475 92.71 0)
      (effects (font (size 1.27 1.27) (thickness 0.15)) (justify left bottom) hide)
    )
    (property "MPN" "CR0402-FX-49R9GLF" (at 241.935 92.71 0)
      (effects (font (size 1.27 1.27) (thickness 0.15)) (justify left bottom) hide)
    )
    (property "Val" "49R9" (at 224.155 112.3949 90)
      (effects (font (size 1.27 1.27) (thickness 0.15)) (justify right))
    )
    (property "License" "Apache-2.0" (at 247.015 92.71 0)
      (effects (font (size 1.27 1.27) (thickness 0.15)) (justify left bottom) hide)
    )
    (property "Author" "Antmicro" (at 249.555 92.71 0)
      (effects (font (size 1.27 1.27) (thickness 0.15)) (justify left bottom) hide)
    )
    (property "Tolerance" "1%" (at 231.775 92.71 0)
      (effects (font (size 1.27 1.27)) (justify left bottom) hide)
    )
    (pin "1")
    (pin "2")
    (instances
      (project "kria-k26-devboard"
        (path ""
          (reference "R4") (unit 1)
        )
      )
    )
  )

  (symbol (lib_id "kria-k26-devboard:R_49R9_0402") (at 217.805 113.03 90) (unit 1)
    (in_bom yes) (on_board yes) (dnp no) (fields_autoplaced)
    (property "Reference" "R3" (at 215.265 109.22 90)
      (effects (font (size 1.524 1.524)) (justify left))
    )
    (property "Value" "R_49R9_0402" (at 230.505 92.71 0)
      (effects (font (size 1.27 1.27) (thickness 0.15)) (justify left bottom) hide)
    )
    (property "Footprint" "kria-k26-devboard-footprints:R_0402_1005Metric" (at 233.045 92.71 0)
      (effects (font (size 1.27 1.27) (thickness 0.15)) (justify left bottom) hide)
    )
    (property "Datasheet" "https://www.bourns.com/docs/product-datasheets/cr.pdf" (at 235.585 92.71 0)
      (effects (font (size 1.27 1.27) (thickness 0.15)) (justify left bottom) hide)
    )
    (property "Manufacturer" "Bourns" (at 240.665 92.71 0)
      (effects (font (size 1.27 1.27) (thickness 0.15)) (justify left bottom) hide)
    )
    (property "MPN" "CR0402-FX-49R9GLF" (at 238.125 92.71 0)
      (effects (font (size 1.27 1.27) (thickness 0.15)) (justify left bottom) hide)
    )
    (property "Val" "49R9" (at 215.265 112.3949 90)
      (effects (font (size 1.27 1.27) (thickness 0.15)) (justify left))
    )
    (property "License" "Apache-2.0" (at 243.205 92.71 0)
      (effects (font (size 1.27 1.27) (thickness 0.15)) (justify left bottom) hide)
    )
    (property "Author" "Antmicro" (at 245.745 92.71 0)
      (effects (font (size 1.27 1.27) (thickness 0.15)) (justify left bottom) hide)
    )
    (property "Tolerance" "1%" (at 227.965 92.71 0)
      (effects (font (size 1.27 1.27)) (justify left bottom) hide)
    )
    (pin "1")
    (pin "2")
    (instances
      (project "kria-k26-devboard"
        (path ""
          (reference "R3") (unit 1)
        )
      )
    )
  )

  (symbol (lib_id "kria-k26-devboard:R_2k49_0402") (at 209.55 85.725 270) (unit 1)
    (in_bom yes) (on_board yes) (dnp no) (fields_autoplaced)
    (property "Reference" "R5" (at 212.09 86.995 90)
      (effects (font (size 1.524 1.524)) (justify left))
    )
    (property "Value" "R_2k49_0402" (at 196.85 106.045 0)
      (effects (font (size 1.27 1.27) (thickness 0.15)) (justify left bottom) hide)
    )
    (property "Footprint" "kria-k26-devboard-footprints:R_0402_1005Metric" (at 194.31 106.045 0)
      (effects (font (size 1.27 1.27) (thickness 0.15)) (justify left bottom) hide)
    )
    (property "Datasheet" "https://www.bourns.com/docs/product-datasheets/cr.pdf" (at 191.77 106.045 0)
      (effects (font (size 1.27 1.27) (thickness 0.15)) (justify left bottom) hide)
    )
    (property "Manufacturer" "Bourns" (at 186.69 106.045 0)
      (effects (font (size 1.27 1.27) (thickness 0.15)) (justify left bottom) hide)
    )
    (property "MPN" "CR0402-FX-2491GLF" (at 189.23 106.045 0)
      (effects (font (size 1.27 1.27) (thickness 0.15)) (justify left bottom) hide)
    )
    (property "Val" "2k49" (at 212.09 90.1699 90)
      (effects (font (size 1.27 1.27) (thickness 0.15)) (justify left))
    )
    (property "License" "Apache-2.0" (at 184.15 106.045 0)
      (effects (font (size 1.27 1.27) (thickness 0.15)) (justify left bottom) hide)
    )
    (property "Author" "Antmicro" (at 181.61 106.045 0)
      (effects (font (size 1.27 1.27) (thickness 0.15)) (justify left bottom) hide)
    )
    (property "Tolerance" "1%" (at 199.39 106.045 0)
      (effects (font (size 1.27 1.27)) (justify left bottom) hide)
    )
    (pin "1")
    (pin "2")
    (instances
      (project "kria-k26-devboard"
        (path ""
          (reference "R5") (unit 1)
        )
      )
    )
  )

  (symbol (lib_id "kria-k26-devboard:R_1k5_0402") (at 209.55 93.345 270) (unit 1)
    (in_bom yes) (on_board yes) (dnp no) (fields_autoplaced)
    (property "Reference" "R6" (at 212.09 94.615 90)
      (effects (font (size 1.524 1.524)) (justify left))
    )
    (property "Value" "R_1k5_0402" (at 196.85 113.665 0)
      (effects (font (size 1.27 1.27) (thickness 0.15)) (justify left bottom) hide)
    )
    (property "Footprint" "kria-k26-devboard-footprints:R_0402_1005Metric" (at 194.31 113.665 0)
      (effects (font (size 1.27 1.27) (thickness 0.15)) (justify left bottom) hide)
    )
    (property "Datasheet" "https://www.bourns.com/docs/product-datasheets/cr.pdf" (at 191.77 113.665 0)
      (effects (font (size 1.27 1.27) (thickness 0.15)) (justify left bottom) hide)
    )
    (property "Manufacturer" "Bourns" (at 186.69 113.665 0)
      (effects (font (size 1.27 1.27) (thickness 0.15)) (justify left bottom) hide)
    )
    (property "MPN" "CR0402-FX-1501GLF" (at 189.23 113.665 0)
      (effects (font (size 1.27 1.27) (thickness 0.15)) (justify left bottom) hide)
    )
    (property "Val" "1k5" (at 212.09 97.7899 90)
      (effects (font (size 1.27 1.27) (thickness 0.15)) (justify left))
    )
    (property "License" "Apache-2.0" (at 184.15 113.665 0)
      (effects (font (size 1.27 1.27) (thickness 0.15)) (justify left bottom) hide)
    )
    (property "Author" "Antmicro" (at 181.61 113.665 0)
      (effects (font (size 1.27 1.27) (thickness 0.15)) (justify left bottom) hide)
    )
    (property "Tolerance" "1%" (at 199.39 113.665 0)
      (effects (font (size 1.27 1.27)) (justify left bottom) hide)
    )
    (pin "1")
    (pin "2")
    (instances
      (project "kria-k26-devboard"
        (path ""
          (reference "R6") (unit 1)
        )
      )
    )
  )

  (symbol (lib_id "kria-k26-devboard:GND") (at 209.55 98.425 0) (unit 1)
    (in_bom yes) (on_board yes) (dnp no) (fields_autoplaced)
    (property "Reference" "#PWR011" (at 209.55 104.775 0)
      (effects (font (size 1.27 1.27)) hide)
    )
    (property "Value" "GND" (at 209.55 103.505 0)
      (effects (font (size 1.27 1.27)))
    )
    (property "Footprint" "" (at 218.44 106.045 0)
      (effects (font (size 1.27 1.27) (thickness 0.15)) (justify left bottom) hide)
    )
    (property "Datasheet" "" (at 218.44 111.125 0)
      (effects (font (size 1.27 1.27) (thickness 0.15)) (justify left bottom) hide)
    )
    (property "Author" "Antmicro" (at 218.44 106.045 0)
      (effects (font (size 1.27 1.27) (thickness 0.15)) (justify left bottom) hide)
    )
    (property "License" "Apache-2.0" (at 218.44 108.585 0)
      (effects (font (size 1.27 1.27) (thickness 0.15)) (justify left bottom) hide)
    )
    (pin "1")
    (instances
      (project "kria-k26-devboard"
        (path ""
          (reference "#PWR011") (unit 1)
        )
      )
    )
  )

  (symbol (lib_id "kria-k26-devboard:C_100n_0402") (at 236.22 114.935 0) (unit 1)
    (in_bom yes) (on_board yes) (dnp no)
    (property "Reference" "C10" (at 235.585 113.665 0)
      (effects (font (size 1.524 1.524)))
    )
    (property "Value" "C_100n_0402" (at 256.54 125.095 0)
      (effects (font (size 1.27 1.27) (thickness 0.15)) (justify left bottom) hide)
    )
    (property "Footprint" "kria-k26-devboard-footprints:C_0402_1005Metric" (at 256.54 127.635 0)
      (effects (font (size 1.27 1.27) (thickness 0.15)) (justify left bottom) hide)
    )
    (property "Datasheet" "https://search.murata.co.jp/Ceramy/image/img/A01X/G101/ENG/GRM155R61H104KE14-01.pdf" (at 256.54 130.175 0)
      (effects (font (size 1.27 1.27) (thickness 0.15)) (justify left bottom) hide)
    )
    (property "Manufacturer" "Murata" (at 256.54 135.255 0)
      (effects (font (size 1.27 1.27) (thickness 0.15)) (justify left bottom) hide)
    )
    (property "MPN" "GRM155R61H104KE14D" (at 256.54 132.715 0)
      (effects (font (size 1.27 1.27) (thickness 0.15)) (justify left bottom) hide)
    )
    (property "Val" "100n" (at 241.935 113.665 0)
      (effects (font (size 1.27 1.27) (thickness 0.15)))
    )
    (property "License" "Apache-2.0" (at 256.54 137.795 0)
      (effects (font (size 1.27 1.27) (thickness 0.15)) (justify left bottom) hide)
    )
    (property "Author" "Antmicro" (at 256.54 140.335 0)
      (effects (font (size 1.27 1.27) (thickness 0.15)) (justify left bottom) hide)
    )
    (property "Voltage" "50V" (at 256.54 142.875 0)
      (effects (font (size 1.27 1.27)) (justify left bottom) hide)
    )
    (property "Dielectric" "X5R" (at 256.54 145.415 0)
      (effects (font (size 1.27 1.27)) (justify left bottom) hide)
    )
    (pin "1")
    (pin "2")
    (instances
      (project "kria-k26-devboard"
        (path ""
          (reference "C10") (unit 1)
        )
      )
    )
  )

  (symbol (lib_id "kria-k26-devboard:C_100n_0402") (at 236.22 120.015 0) (unit 1)
    (in_bom yes) (on_board yes) (dnp no)
    (property "Reference" "C11" (at 235.585 118.745 0)
      (effects (font (size 1.524 1.524)))
    )
    (property "Value" "C_100n_0402" (at 256.54 130.175 0)
      (effects (font (size 1.27 1.27) (thickness 0.15)) (justify left bottom) hide)
    )
    (property "Footprint" "kria-k26-devboard-footprints:C_0402_1005Metric" (at 256.54 132.715 0)
      (effects (font (size 1.27 1.27) (thickness 0.15)) (justify left bottom) hide)
    )
    (property "Datasheet" "https://search.murata.co.jp/Ceramy/image/img/A01X/G101/ENG/GRM155R61H104KE14-01.pdf" (at 256.54 135.255 0)
      (effects (font (size 1.27 1.27) (thickness 0.15)) (justify left bottom) hide)
    )
    (property "Manufacturer" "Murata" (at 256.54 140.335 0)
      (effects (font (size 1.27 1.27) (thickness 0.15)) (justify left bottom) hide)
    )
    (property "MPN" "GRM155R61H104KE14D" (at 256.54 137.795 0)
      (effects (font (size 1.27 1.27) (thickness 0.15)) (justify left bottom) hide)
    )
    (property "Val" "100n" (at 241.935 118.745 0)
      (effects (font (size 1.27 1.27) (thickness 0.15)))
    )
    (property "License" "Apache-2.0" (at 256.54 142.875 0)
      (effects (font (size 1.27 1.27) (thickness 0.15)) (justify left bottom) hide)
    )
    (property "Author" "Antmicro" (at 256.54 145.415 0)
      (effects (font (size 1.27 1.27) (thickness 0.15)) (justify left bottom) hide)
    )
    (property "Voltage" "50V" (at 256.54 147.955 0)
      (effects (font (size 1.27 1.27)) (justify left bottom) hide)
    )
    (property "Dielectric" "X5R" (at 256.54 150.495 0)
      (effects (font (size 1.27 1.27)) (justify left bottom) hide)
    )
    (pin "1")
    (pin "2")
    (instances
      (project "kria-k26-devboard"
        (path ""
          (reference "C11") (unit 1)
        )
      )
    )
  )

  (symbol (lib_id "kria-k26-devboard:C_100n_0402") (at 212.09 149.86 0) (unit 1)
    (in_bom yes) (on_board yes) (dnp no)
    (property "Reference" "C6" (at 211.455 148.59 0)
      (effects (font (size 1.524 1.524)))
    )
    (property "Value" "C_100n_0402" (at 232.41 160.02 0)
      (effects (font (size 1.27 1.27) (thickness 0.15)) (justify left bottom) hide)
    )
    (property "Footprint" "kria-k26-devboard-footprints:C_0402_1005Metric" (at 232.41 162.56 0)
      (effects (font (size 1.27 1.27) (thickness 0.15)) (justify left bottom) hide)
    )
    (property "Datasheet" "https://search.murata.co.jp/Ceramy/image/img/A01X/G101/ENG/GRM155R61H104KE14-01.pdf" (at 232.41 165.1 0)
      (effects (font (size 1.27 1.27) (thickness 0.15)) (justify left bottom) hide)
    )
    (property "Manufacturer" "Murata" (at 232.41 170.18 0)
      (effects (font (size 1.27 1.27) (thickness 0.15)) (justify left bottom) hide)
    )
    (property "MPN" "GRM155R61H104KE14D" (at 232.41 167.64 0)
      (effects (font (size 1.27 1.27) (thickness 0.15)) (justify left bottom) hide)
    )
    (property "Val" "100n" (at 217.805 148.59 0)
      (effects (font (size 1.27 1.27) (thickness 0.15)))
    )
    (property "License" "Apache-2.0" (at 232.41 172.72 0)
      (effects (font (size 1.27 1.27) (thickness 0.15)) (justify left bottom) hide)
    )
    (property "Author" "Antmicro" (at 232.41 175.26 0)
      (effects (font (size 1.27 1.27) (thickness 0.15)) (justify left bottom) hide)
    )
    (property "Voltage" "50V" (at 232.41 177.8 0)
      (effects (font (size 1.27 1.27)) (justify left bottom) hide)
    )
    (property "Dielectric" "X5R" (at 232.41 180.34 0)
      (effects (font (size 1.27 1.27)) (justify left bottom) hide)
    )
    (pin "1")
    (pin "2")
    (instances
      (project "kria-k26-devboard"
        (path ""
          (reference "C6") (unit 1)
        )
      )
    )
  )

  (symbol (lib_id "kria-k26-devboard:C_100n_0402") (at 212.09 153.67 0) (unit 1)
    (in_bom yes) (on_board yes) (dnp no)
    (property "Reference" "C7" (at 211.455 152.4 0)
      (effects (font (size 1.524 1.524)))
    )
    (property "Value" "C_100n_0402" (at 232.41 163.83 0)
      (effects (font (size 1.27 1.27) (thickness 0.15)) (justify left bottom) hide)
    )
    (property "Footprint" "kria-k26-devboard-footprints:C_0402_1005Metric" (at 232.41 166.37 0)
      (effects (font (size 1.27 1.27) (thickness 0.15)) (justify left bottom) hide)
    )
    (property "Datasheet" "https://search.murata.co.jp/Ceramy/image/img/A01X/G101/ENG/GRM155R61H104KE14-01.pdf" (at 232.41 168.91 0)
      (effects (font (size 1.27 1.27) (thickness 0.15)) (justify left bottom) hide)
    )
    (property "Manufacturer" "Murata" (at 232.41 173.99 0)
      (effects (font (size 1.27 1.27) (thickness 0.15)) (justify left bottom) hide)
    )
    (property "MPN" "GRM155R61H104KE14D" (at 232.41 171.45 0)
      (effects (font (size 1.27 1.27) (thickness 0.15)) (justify left bottom) hide)
    )
    (property "Val" "100n" (at 217.805 152.4 0)
      (effects (font (size 1.27 1.27) (thickness 0.15)))
    )
    (property "License" "Apache-2.0" (at 232.41 176.53 0)
      (effects (font (size 1.27 1.27) (thickness 0.15)) (justify left bottom) hide)
    )
    (property "Author" "Antmicro" (at 232.41 179.07 0)
      (effects (font (size 1.27 1.27) (thickness 0.15)) (justify left bottom) hide)
    )
    (property "Voltage" "50V" (at 232.41 181.61 0)
      (effects (font (size 1.27 1.27)) (justify left bottom) hide)
    )
    (property "Dielectric" "X5R" (at 232.41 184.15 0)
      (effects (font (size 1.27 1.27)) (justify left bottom) hide)
    )
    (pin "1")
    (pin "2")
    (instances
      (project "kria-k26-devboard"
        (path ""
          (reference "C7") (unit 1)
        )
      )
    )
  )

  (symbol (lib_id "kria-k26-devboard:C_100n_0402") (at 212.09 161.925 0) (unit 1)
    (in_bom yes) (on_board yes) (dnp no)
    (property "Reference" "C8" (at 212.09 160.655 0)
      (effects (font (size 1.524 1.524)))
    )
    (property "Value" "C_100n_0402" (at 232.41 172.085 0)
      (effects (font (size 1.27 1.27) (thickness 0.15)) (justify left bottom) hide)
    )
    (property "Footprint" "kria-k26-devboard-footprints:C_0402_1005Metric" (at 232.41 174.625 0)
      (effects (font (size 1.27 1.27) (thickness 0.15)) (justify left bottom) hide)
    )
    (property "Datasheet" "https://search.murata.co.jp/Ceramy/image/img/A01X/G101/ENG/GRM155R61H104KE14-01.pdf" (at 232.41 177.165 0)
      (effects (font (size 1.27 1.27) (thickness 0.15)) (justify left bottom) hide)
    )
    (property "Manufacturer" "Murata" (at 232.41 182.245 0)
      (effects (font (size 1.27 1.27) (thickness 0.15)) (justify left bottom) hide)
    )
    (property "MPN" "GRM155R61H104KE14D" (at 232.41 179.705 0)
      (effects (font (size 1.27 1.27) (thickness 0.15)) (justify left bottom) hide)
    )
    (property "Val" "100n" (at 217.805 160.655 0)
      (effects (font (size 1.27 1.27) (thickness 0.15)))
    )
    (property "License" "Apache-2.0" (at 232.41 184.785 0)
      (effects (font (size 1.27 1.27) (thickness 0.15)) (justify left bottom) hide)
    )
    (property "Author" "Antmicro" (at 232.41 187.325 0)
      (effects (font (size 1.27 1.27) (thickness 0.15)) (justify left bottom) hide)
    )
    (property "Voltage" "50V" (at 232.41 189.865 0)
      (effects (font (size 1.27 1.27)) (justify left bottom) hide)
    )
    (property "Dielectric" "X5R" (at 232.41 192.405 0)
      (effects (font (size 1.27 1.27)) (justify left bottom) hide)
    )
    (pin "1")
    (pin "2")
    (instances
      (project "kria-k26-devboard"
        (path ""
          (reference "C8") (unit 1)
        )
      )
    )
  )

  (symbol (lib_id "kria-k26-devboard:C_100n_0402") (at 212.09 167.005 0) (unit 1)
    (in_bom yes) (on_board yes) (dnp no)
    (property "Reference" "C9" (at 212.09 165.735 0)
      (effects (font (size 1.524 1.524)))
    )
    (property "Value" "C_100n_0402" (at 232.41 177.165 0)
      (effects (font (size 1.27 1.27) (thickness 0.15)) (justify left bottom) hide)
    )
    (property "Footprint" "kria-k26-devboard-footprints:C_0402_1005Metric" (at 232.41 179.705 0)
      (effects (font (size 1.27 1.27) (thickness 0.15)) (justify left bottom) hide)
    )
    (property "Datasheet" "https://search.murata.co.jp/Ceramy/image/img/A01X/G101/ENG/GRM155R61H104KE14-01.pdf" (at 232.41 182.245 0)
      (effects (font (size 1.27 1.27) (thickness 0.15)) (justify left bottom) hide)
    )
    (property "Manufacturer" "Murata" (at 232.41 187.325 0)
      (effects (font (size 1.27 1.27) (thickness 0.15)) (justify left bottom) hide)
    )
    (property "MPN" "GRM155R61H104KE14D" (at 232.41 184.785 0)
      (effects (font (size 1.27 1.27) (thickness 0.15)) (justify left bottom) hide)
    )
    (property "Val" "100n" (at 217.805 165.735 0)
      (effects (font (size 1.27 1.27) (thickness 0.15)))
    )
    (property "License" "Apache-2.0" (at 232.41 189.865 0)
      (effects (font (size 1.27 1.27) (thickness 0.15)) (justify left bottom) hide)
    )
    (property "Author" "Antmicro" (at 232.41 192.405 0)
      (effects (font (size 1.27 1.27) (thickness 0.15)) (justify left bottom) hide)
    )
    (property "Voltage" "50V" (at 232.41 194.945 0)
      (effects (font (size 1.27 1.27)) (justify left bottom) hide)
    )
    (property "Dielectric" "X5R" (at 232.41 197.485 0)
      (effects (font (size 1.27 1.27)) (justify left bottom) hide)
    )
    (pin "1")
    (pin "2")
    (instances
      (project "kria-k26-devboard"
        (path ""
          (reference "C9") (unit 1)
        )
      )
    )
  )

  (symbol (lib_id "kria-k26-devboard:R_1M_0402") (at 276.225 188.595 0) (unit 1)
    (in_bom yes) (on_board yes) (dnp no)
    (property "Reference" "R9" (at 273.685 187.325 0)
      (effects (font (size 1.524 1.524)))
    )
    (property "Value" "R_1M_0402" (at 296.545 201.295 0)
      (effects (font (size 1.27 1.27) (thickness 0.15)) (justify left bottom) hide)
    )
    (property "Footprint" "kria-k26-devboard-footprints:R_0402_1005Metric" (at 296.545 203.835 0)
      (effects (font (size 1.27 1.27) (thickness 0.15)) (justify left bottom) hide)
    )
    (property "Datasheet" "https://www.bourns.com/docs/product-datasheets/cr.pdf" (at 296.545 206.375 0)
      (effects (font (size 1.27 1.27) (thickness 0.15)) (justify left bottom) hide)
    )
    (property "Manufacturer" "Bourns" (at 296.545 211.455 0)
      (effects (font (size 1.27 1.27) (thickness 0.15)) (justify left bottom) hide)
    )
    (property "MPN" "CR0402-FX-1004GLF" (at 296.545 208.915 0)
      (effects (font (size 1.27 1.27) (thickness 0.15)) (justify left bottom) hide)
    )
    (property "Val" "1M" (at 282.575 187.325 0)
      (effects (font (size 1.27 1.27) (thickness 0.15)))
    )
    (property "License" "Apache-2.0" (at 296.545 213.995 0)
      (effects (font (size 1.27 1.27) (thickness 0.15)) (justify left bottom) hide)
    )
    (property "Author" "Antmicro" (at 296.545 216.535 0)
      (effects (font (size 1.27 1.27) (thickness 0.15)) (justify left bottom) hide)
    )
    (property "Tolerance" "1%" (at 296.545 198.755 0)
      (effects (font (size 1.27 1.27)) (justify left bottom) hide)
    )
    (pin "1")
    (pin "2")
    (instances
      (project "kria-k26-devboard"
        (path ""
          (reference "R9") (unit 1)
        )
      )
    )
  )

  (symbol (lib_id "kria-k26-devboard:R_1M_0402") (at 281.305 186.055 180) (unit 1)
    (in_bom yes) (on_board yes) (dnp no)
    (property "Reference" "R12" (at 274.32 184.785 0)
      (effects (font (size 1.524 1.524)))
    )
    (property "Value" "R_1M_0402" (at 260.985 173.355 0)
      (effects (font (size 1.27 1.27) (thickness 0.15)) (justify left bottom) hide)
    )
    (property "Footprint" "kria-k26-devboard-footprints:R_0402_1005Metric" (at 260.985 170.815 0)
      (effects (font (size 1.27 1.27) (thickness 0.15)) (justify left bottom) hide)
    )
    (property "Datasheet" "https://www.bourns.com/docs/product-datasheets/cr.pdf" (at 260.985 168.275 0)
      (effects (font (size 1.27 1.27) (thickness 0.15)) (justify left bottom) hide)
    )
    (property "Manufacturer" "Bourns" (at 260.985 163.195 0)
      (effects (font (size 1.27 1.27) (thickness 0.15)) (justify left bottom) hide)
    )
    (property "MPN" "CR0402-FX-1004GLF" (at 260.985 165.735 0)
      (effects (font (size 1.27 1.27) (thickness 0.15)) (justify left bottom) hide)
    )
    (property "Val" "1M" (at 282.575 184.785 0)
      (effects (font (size 1.27 1.27) (thickness 0.15)))
    )
    (property "License" "Apache-2.0" (at 260.985 160.655 0)
      (effects (font (size 1.27 1.27) (thickness 0.15)) (justify left bottom) hide)
    )
    (property "Author" "Antmicro" (at 260.985 158.115 0)
      (effects (font (size 1.27 1.27) (thickness 0.15)) (justify left bottom) hide)
    )
    (property "Tolerance" "1%" (at 260.985 175.895 0)
      (effects (font (size 1.27 1.27)) (justify left bottom) hide)
    )
    (pin "1")
    (pin "2")
    (instances
      (project "kria-k26-devboard"
        (path ""
          (reference "R12") (unit 1)
        )
      )
    )
  )

  (symbol (lib_id "kria-k26-devboard:GND") (at 285.115 197.485 0) (unit 1)
    (in_bom yes) (on_board yes) (dnp no) (fields_autoplaced)
    (property "Reference" "#PWR015" (at 285.115 203.835 0)
      (effects (font (size 1.27 1.27)) hide)
    )
    (property "Value" "GND" (at 285.115 202.565 0)
      (effects (font (size 1.27 1.27)))
    )
    (property "Footprint" "" (at 294.005 205.105 0)
      (effects (font (size 1.27 1.27) (thickness 0.15)) (justify left bottom) hide)
    )
    (property "Datasheet" "" (at 294.005 210.185 0)
      (effects (font (size 1.27 1.27) (thickness 0.15)) (justify left bottom) hide)
    )
    (property "Author" "Antmicro" (at 294.005 205.105 0)
      (effects (font (size 1.27 1.27) (thickness 0.15)) (justify left bottom) hide)
    )
    (property "License" "Apache-2.0" (at 294.005 207.645 0)
      (effects (font (size 1.27 1.27) (thickness 0.15)) (justify left bottom) hide)
    )
    (pin "1")
    (instances
      (project "kria-k26-devboard"
        (path ""
          (reference "#PWR015") (unit 1)
        )
      )
    )
  )

  (symbol (lib_id "kria-k26-devboard:R_0R_0402") (at 276.225 191.135 0) (unit 1)
    (in_bom yes) (on_board yes) (dnp no)
    (property "Reference" "R10" (at 274.32 189.865 0)
      (effects (font (size 1.524 1.524)))
    )
    (property "Value" "R_0R_0402" (at 296.545 203.835 0)
      (effects (font (size 1.27 1.27) (thickness 0.15)) (justify left bottom) hide)
    )
    (property "Footprint" "kria-k26-devboard-footprints:R_0402_1005Metric" (at 296.545 206.375 0)
      (effects (font (size 1.27 1.27) (thickness 0.15)) (justify left bottom) hide)
    )
    (property "Datasheet" "https://industrial.panasonic.com/cdbs/www-data/pdf/RDA0000/AOA0000C301.pdf" (at 296.545 208.915 0)
      (effects (font (size 1.27 1.27) (thickness 0.15)) (justify left bottom) hide)
    )
    (property "Manufacturer" "Panasonic" (at 296.545 213.995 0)
      (effects (font (size 1.27 1.27) (thickness 0.15)) (justify left bottom) hide)
    )
    (property "MPN" "ERJ2GE0R00X" (at 296.545 211.455 0)
      (effects (font (size 1.27 1.27) (thickness 0.15)) (justify left bottom) hide)
    )
    (property "Val" "0R" (at 282.575 189.865 0)
      (effects (font (size 1.27 1.27) (thickness 0.15)))
    )
    (property "License" "Apache-2.0" (at 296.545 216.535 0)
      (effects (font (size 1.27 1.27) (thickness 0.15)) (justify left bottom) hide)
    )
    (property "Author" "Antmicro" (at 296.545 219.075 0)
      (effects (font (size 1.27 1.27) (thickness 0.15)) (justify left bottom) hide)
    )
    (property "Tolerance" "~" (at 296.545 201.295 0)
      (effects (font (size 1.27 1.27)) (justify left bottom) hide)
    )
    (property "Current" "1A" (at 296.545 221.615 0)
      (effects (font (size 1.27 1.27) (thickness 0.15)) (justify left bottom) hide)
    )
    (pin "1")
    (pin "2")
    (instances
      (project "kria-k26-devboard"
        (path ""
          (reference "R10") (unit 1)
        )
      )
    )
  )

  (symbol (lib_id "kria-k26-devboard:GND") (at 273.05 197.485 0) (unit 1)
    (in_bom yes) (on_board yes) (dnp no) (fields_autoplaced)
    (property "Reference" "#PWR016" (at 273.05 203.835 0)
      (effects (font (size 1.27 1.27)) hide)
    )
    (property "Value" "GND" (at 273.05 202.565 0)
      (effects (font (size 1.27 1.27)))
    )
    (property "Footprint" "" (at 281.94 205.105 0)
      (effects (font (size 1.27 1.27) (thickness 0.15)) (justify left bottom) hide)
    )
    (property "Datasheet" "" (at 281.94 210.185 0)
      (effects (font (size 1.27 1.27) (thickness 0.15)) (justify left bottom) hide)
    )
    (property "Author" "Antmicro" (at 281.94 205.105 0)
      (effects (font (size 1.27 1.27) (thickness 0.15)) (justify left bottom) hide)
    )
    (property "License" "Apache-2.0" (at 281.94 207.645 0)
      (effects (font (size 1.27 1.27) (thickness 0.15)) (justify left bottom) hide)
    )
    (pin "1")
    (instances
      (project "kria-k26-devboard"
        (path ""
          (reference "#PWR016") (unit 1)
        )
      )
    )
  )

  (symbol (lib_id "kria-k26-devboard:R_100k_0402") (at 247.65 97.79 270) (unit 1)
    (in_bom yes) (on_board yes) (dnp no) (fields_autoplaced)
    (property "Reference" "R8" (at 250.19 99.06 90)
      (effects (font (size 1.524 1.524)) (justify left))
    )
    (property "Value" "R_100k_0402" (at 234.95 118.11 0)
      (effects (font (size 1.27 1.27) (thickness 0.15)) (justify left bottom) hide)
    )
    (property "Footprint" "kria-k26-devboard-footprints:R_0402_1005Metric" (at 232.41 118.11 0)
      (effects (font (size 1.27 1.27) (thickness 0.15)) (justify left bottom) hide)
    )
    (property "Datasheet" "https://www.bourns.com/docs/product-datasheets/cr.pdf" (at 229.87 118.11 0)
      (effects (font (size 1.27 1.27) (thickness 0.15)) (justify left bottom) hide)
    )
    (property "Manufacturer" "Bourns" (at 224.79 118.11 0)
      (effects (font (size 1.27 1.27) (thickness 0.15)) (justify left bottom) hide)
    )
    (property "MPN" "CR0402-FX-1003GLF" (at 227.33 118.11 0)
      (effects (font (size 1.27 1.27) (thickness 0.15)) (justify left bottom) hide)
    )
    (property "Val" "100k" (at 250.19 102.2349 90)
      (effects (font (size 1.27 1.27) (thickness 0.15)) (justify left))
    )
    (property "License" "Apache-2.0" (at 222.25 118.11 0)
      (effects (font (size 1.27 1.27) (thickness 0.15)) (justify left bottom) hide)
    )
    (property "Author" "Antmicro" (at 219.71 118.11 0)
      (effects (font (size 1.27 1.27) (thickness 0.15)) (justify left bottom) hide)
    )
    (property "Tolerance" "1%" (at 237.49 118.11 0)
      (effects (font (size 1.27 1.27)) (justify left bottom) hide)
    )
    (pin "1")
    (pin "2")
    (instances
      (project "kria-k26-devboard"
        (path ""
          (reference "R8") (unit 1)
        )
      )
    )
  )

  (symbol (lib_id "kria-k26-devboard:R_100k_0402") (at 247.65 86.36 270) (unit 1)
    (in_bom yes) (on_board yes) (dnp no) (fields_autoplaced)
    (property "Reference" "R7" (at 250.19 87.63 90)
      (effects (font (size 1.524 1.524)) (justify left))
    )
    (property "Value" "R_100k_0402" (at 234.95 106.68 0)
      (effects (font (size 1.27 1.27) (thickness 0.15)) (justify left bottom) hide)
    )
    (property "Footprint" "kria-k26-devboard-footprints:R_0402_1005Metric" (at 232.41 106.68 0)
      (effects (font (size 1.27 1.27) (thickness 0.15)) (justify left bottom) hide)
    )
    (property "Datasheet" "https://www.bourns.com/docs/product-datasheets/cr.pdf" (at 229.87 106.68 0)
      (effects (font (size 1.27 1.27) (thickness 0.15)) (justify left bottom) hide)
    )
    (property "Manufacturer" "Bourns" (at 224.79 106.68 0)
      (effects (font (size 1.27 1.27) (thickness 0.15)) (justify left bottom) hide)
    )
    (property "MPN" "CR0402-FX-1003GLF" (at 227.33 106.68 0)
      (effects (font (size 1.27 1.27) (thickness 0.15)) (justify left bottom) hide)
    )
    (property "Val" "100k" (at 250.19 90.8049 90)
      (effects (font (size 1.27 1.27) (thickness 0.15)) (justify left))
    )
    (property "License" "Apache-2.0" (at 222.25 106.68 0)
      (effects (font (size 1.27 1.27) (thickness 0.15)) (justify left bottom) hide)
    )
    (property "Author" "Antmicro" (at 219.71 106.68 0)
      (effects (font (size 1.27 1.27) (thickness 0.15)) (justify left bottom) hide)
    )
    (property "Tolerance" "1%" (at 237.49 106.68 0)
      (effects (font (size 1.27 1.27)) (justify left bottom) hide)
    )
    (pin "1")
    (pin "2")
    (instances
      (project "kria-k26-devboard"
        (path ""
          (reference "R7") (unit 1)
        )
      )
    )
  )

  (symbol (lib_id "kria-k26-devboard:GND") (at 247.65 102.87 0) (unit 1)
    (in_bom yes) (on_board yes) (dnp no) (fields_autoplaced)
    (property "Reference" "#PWR013" (at 247.65 109.22 0)
      (effects (font (size 1.27 1.27)) hide)
    )
    (property "Value" "GND" (at 247.65 107.95 0)
      (effects (font (size 1.27 1.27)))
    )
    (property "Footprint" "" (at 256.54 110.49 0)
      (effects (font (size 1.27 1.27) (thickness 0.15)) (justify left bottom) hide)
    )
    (property "Datasheet" "" (at 256.54 115.57 0)
      (effects (font (size 1.27 1.27) (thickness 0.15)) (justify left bottom) hide)
    )
    (property "Author" "Antmicro" (at 256.54 110.49 0)
      (effects (font (size 1.27 1.27) (thickness 0.15)) (justify left bottom) hide)
    )
    (property "License" "Apache-2.0" (at 256.54 113.03 0)
      (effects (font (size 1.27 1.27) (thickness 0.15)) (justify left bottom) hide)
    )
    (pin "1")
    (instances
      (project "kria-k26-devboard"
        (path ""
          (reference "#PWR013") (unit 1)
        )
      )
    )
  )

  (symbol (lib_id "kria-k26-devboard:GND") (at 257.175 120.015 0) (unit 1)
    (in_bom yes) (on_board yes) (dnp no) (fields_autoplaced)
    (property "Reference" "#PWR012" (at 257.175 126.365 0)
      (effects (font (size 1.27 1.27)) hide)
    )
    (property "Value" "GND" (at 257.175 125.095 0)
      (effects (font (size 1.27 1.27)))
    )
    (property "Footprint" "" (at 266.065 127.635 0)
      (effects (font (size 1.27 1.27) (thickness 0.15)) (justify left bottom) hide)
    )
    (property "Datasheet" "" (at 266.065 132.715 0)
      (effects (font (size 1.27 1.27) (thickness 0.15)) (justify left bottom) hide)
    )
    (property "Author" "Antmicro" (at 266.065 127.635 0)
      (effects (font (size 1.27 1.27) (thickness 0.15)) (justify left bottom) hide)
    )
    (property "License" "Apache-2.0" (at 266.065 130.175 0)
      (effects (font (size 1.27 1.27) (thickness 0.15)) (justify left bottom) hide)
    )
    (pin "1")
    (instances
      (project "kria-k26-devboard"
        (path ""
          (reference "#PWR012") (unit 1)
        )
      )
    )
  )

  (symbol (lib_id "kria-k26-devboard:R_100k_0402") (at 239.395 193.675 90) (mirror x) (unit 1)
    (in_bom yes) (on_board yes) (dnp no) (fields_autoplaced)
    (property "Reference" "R11" (at 236.855 194.945 90)
      (effects (font (size 1.524 1.524)) (justify left))
    )
    (property "Value" "R_100k_0402" (at 252.095 213.995 0)
      (effects (font (size 1.27 1.27) (thickness 0.15)) (justify left bottom) hide)
    )
    (property "Footprint" "kria-k26-devboard-footprints:R_0402_1005Metric" (at 254.635 213.995 0)
      (effects (font (size 1.27 1.27) (thickness 0.15)) (justify left bottom) hide)
    )
    (property "Datasheet" "https://www.bourns.com/docs/product-datasheets/cr.pdf" (at 257.175 213.995 0)
      (effects (font (size 1.27 1.27) (thickness 0.15)) (justify left bottom) hide)
    )
    (property "Manufacturer" "Bourns" (at 262.255 213.995 0)
      (effects (font (size 1.27 1.27) (thickness 0.15)) (justify left bottom) hide)
    )
    (property "MPN" "CR0402-FX-1003GLF" (at 259.715 213.995 0)
      (effects (font (size 1.27 1.27) (thickness 0.15)) (justify left bottom) hide)
    )
    (property "Val" "100k" (at 236.855 198.1199 90)
      (effects (font (size 1.27 1.27) (thickness 0.15)) (justify left))
    )
    (property "License" "Apache-2.0" (at 264.795 213.995 0)
      (effects (font (size 1.27 1.27) (thickness 0.15)) (justify left bottom) hide)
    )
    (property "Author" "Antmicro" (at 267.335 213.995 0)
      (effects (font (size 1.27 1.27) (thickness 0.15)) (justify left bottom) hide)
    )
    (property "Tolerance" "1%" (at 249.555 213.995 0)
      (effects (font (size 1.27 1.27)) (justify left bottom) hide)
    )
    (pin "1")
    (pin "2")
    (instances
      (project "kria-k26-devboard"
        (path ""
          (reference "R11") (unit 1)
        )
      )
    )
  )

  (symbol (lib_id "kria-k26-devboard:GND") (at 239.395 198.755 0) (mirror y) (unit 1)
    (in_bom yes) (on_board yes) (dnp no) (fields_autoplaced)
    (property "Reference" "#PWR022" (at 239.395 205.105 0)
      (effects (font (size 1.27 1.27)) hide)
    )
    (property "Value" "GND" (at 239.395 203.835 0)
      (effects (font (size 1.27 1.27)))
    )
    (property "Footprint" "" (at 230.505 206.375 0)
      (effects (font (size 1.27 1.27) (thickness 0.15)) (justify left bottom) hide)
    )
    (property "Datasheet" "" (at 230.505 211.455 0)
      (effects (font (size 1.27 1.27) (thickness 0.15)) (justify left bottom) hide)
    )
    (property "Author" "Antmicro" (at 230.505 206.375 0)
      (effects (font (size 1.27 1.27) (thickness 0.15)) (justify left bottom) hide)
    )
    (property "License" "Apache-2.0" (at 230.505 208.915 0)
      (effects (font (size 1.27 1.27) (thickness 0.15)) (justify left bottom) hide)
    )
    (pin "1")
    (instances
      (project "kria-k26-devboard"
        (path ""
          (reference "#PWR022") (unit 1)
        )
      )
    )
  )

  (symbol (lib_id "kria-k26-devboard:PMEG3010CE_SOD323") (at 224.155 208.915 0) (unit 1)
    (in_bom yes) (on_board yes) (dnp no)
    (property "Reference" "D1" (at 228.6 203.2 0)
      (effects (font (size 1.524 1.524)))
    )
    (property "Value" "PMEG3010CE_SOD323" (at 228.219 205.105 0)
      (effects (font (size 1.27 1.27) (thickness 0.15)) hide)
    )
    (property "Footprint" "kria-k26-devboard-footprints:D_SOD-323F" (at 247.015 219.075 0)
      (effects (font (size 1.27 1.27) (thickness 0.15)) (justify left bottom) hide)
    )
    (property "Datasheet" "https://assets.nexperia.com/documents/data-sheet/PMEG3010CEH_PMEG3010CEJ.pdf" (at 247.015 221.615 0)
      (effects (font (size 1.27 1.27) (thickness 0.15)) (justify left bottom) hide)
    )
    (property "MPN" "PMEG3010CEJ" (at 228.6 205.74 0)
      (effects (font (size 1.27 1.27) (thickness 0.15)))
    )
    (property "Manufacturer" "Nexperia" (at 247.015 226.695 0)
      (effects (font (size 1.27 1.27) (thickness 0.15)) (justify left bottom) hide)
    )
    (property "Author" "Antmicro" (at 247.015 229.235 0)
      (effects (font (size 1.27 1.27) (thickness 0.15)) (justify left bottom) hide)
    )
    (property "License" "Apache-2.0" (at 247.015 231.775 0)
      (effects (font (size 1.27 1.27) (thickness 0.15)) (justify left bottom) hide)
    )
    (pin "A")
    (pin "K")
    (instances
      (project "kria-k26-devboard"
        (path ""
          (reference "D1") (unit 1)
        )
      )
    )
  )

  (symbol (lib_id "kria-k26-devboard:GND") (at 162.56 208.915 0) (unit 1)
    (in_bom yes) (on_board yes) (dnp no) (fields_autoplaced)
    (property "Reference" "#PWR010" (at 162.56 215.265 0)
      (effects (font (size 1.27 1.27)) hide)
    )
    (property "Value" "GND" (at 162.56 213.995 0)
      (effects (font (size 1.27 1.27)))
    )
    (property "Footprint" "" (at 171.45 216.535 0)
      (effects (font (size 1.27 1.27) (thickness 0.15)) (justify left bottom) hide)
    )
    (property "Datasheet" "" (at 171.45 221.615 0)
      (effects (font (size 1.27 1.27) (thickness 0.15)) (justify left bottom) hide)
    )
    (property "Author" "Antmicro" (at 171.45 216.535 0)
      (effects (font (size 1.27 1.27) (thickness 0.15)) (justify left bottom) hide)
    )
    (property "License" "Apache-2.0" (at 171.45 219.075 0)
      (effects (font (size 1.27 1.27) (thickness 0.15)) (justify left bottom) hide)
    )
    (pin "1")
    (instances
      (project "kria-k26-devboard"
        (path ""
          (reference "#PWR010") (unit 1)
        )
      )
    )
  )

  (symbol (lib_id "kria-k26-devboard:C_100n_0402") (at 244.475 212.09 90) (mirror x) (unit 1)
    (in_bom yes) (on_board yes) (dnp no)
    (property "Reference" "C248" (at 243.84 212.725 90)
      (effects (font (size 1.524 1.524)) (justify left))
    )
    (property "Value" "C_100n_0402" (at 254.635 232.41 0)
      (effects (font (size 1.27 1.27) (thickness 0.15)) (justify left bottom) hide)
    )
    (property "Footprint" "kria-k26-devboard-footprints:C_0402_1005Metric" (at 257.175 232.41 0)
      (effects (font (size 1.27 1.27) (thickness 0.15)) (justify left bottom) hide)
    )
    (property "Datasheet" "https://search.murata.co.jp/Ceramy/image/img/A01X/G101/ENG/GRM155R61H104KE14-01.pdf" (at 259.715 232.41 0)
      (effects (font (size 1.27 1.27) (thickness 0.15)) (justify left bottom) hide)
    )
    (property "Manufacturer" "Murata" (at 264.795 232.41 0)
      (effects (font (size 1.27 1.27) (thickness 0.15)) (justify left bottom) hide)
    )
    (property "MPN" "GRM155R61H104KE14D" (at 262.255 232.41 0)
      (effects (font (size 1.27 1.27) (thickness 0.15)) (justify left bottom) hide)
    )
    (property "Val" "100n" (at 243.84 216.535 90)
      (effects (font (size 1.27 1.27) (thickness 0.15)) (justify left))
    )
    (property "License" "Apache-2.0" (at 267.335 232.41 0)
      (effects (font (size 1.27 1.27) (thickness 0.15)) (justify left bottom) hide)
    )
    (property "Author" "Antmicro" (at 269.875 232.41 0)
      (effects (font (size 1.27 1.27) (thickness 0.15)) (justify left bottom) hide)
    )
    (property "Voltage" "50V" (at 272.415 232.41 0)
      (effects (font (size 1.27 1.27)) (justify left bottom) hide)
    )
    (property "Dielectric" "X5R" (at 274.955 232.41 0)
      (effects (font (size 1.27 1.27)) (justify left bottom) hide)
    )
    (pin "1")
    (pin "2")
    (instances
      (project "kria-k26-devboard"
        (path ""
          (reference "C248") (unit 1)
        )
      )
    )
  )

  (symbol (lib_id "kria-k26-devboard:TPD4E05U06QDQARQ1") (at 163.83 197.485 0) (unit 1)
    (in_bom yes) (on_board yes) (dnp no)
    (property "Reference" "U3" (at 167.64 193.04 0)
      (effects (font (size 1.27 1.27) (thickness 0.15)) (justify left))
    )
    (property "Value" "TPD4E05U06QDQARQ1" (at 165.1 210.82 0)
      (effects (font (size 1.27 1.27) (thickness 0.15)) (justify left))
    )
    (property "Footprint" "kria-k26-devboard-footprints:USON-10_2.5x1mm_P0.5mm" (at 187.96 202.565 0)
      (effects (font (size 1.27 1.27) (thickness 0.15)) (justify left bottom) hide)
    )
    (property "Datasheet" "https://www.ti.com/lit/ds/symlink/tpd4e05u06-q1.pdf?HQS=dis-mous-null-mousermode-dsf-pf-null-wwe&ts=1663591265741&ref_url=https%253A%252F%252Fwww.mouser.com%252F" (at 187.96 205.105 0)
      (effects (font (size 1.27 1.27) (thickness 0.15)) (justify left bottom) hide)
    )
    (property "Manufacturer" "Texas Instruments" (at 187.96 207.645 0)
      (effects (font (size 1.27 1.27) (thickness 0.15)) (justify left bottom) hide)
    )
    (property "MPN" "TPD4E05U06QDQARQ1" (at 187.96 210.185 0)
      (effects (font (size 1.27 1.27) (thickness 0.15)) (justify left bottom) hide)
    )
    (property "Author" "Antmicro" (at 187.96 212.725 0)
      (effects (font (size 1.27 1.27) (thickness 0.15)) (justify left bottom) hide)
    )
    (property "License" "Apache-2.0" (at 187.96 215.265 0)
      (effects (font (size 1.27 1.27) (thickness 0.15)) (justify left bottom) hide)
    )
    (pin "1")
    (pin "10")
    (pin "2")
    (pin "3")
    (pin "4")
    (pin "5")
    (pin "6")
    (pin "7")
    (pin "8")
    (pin "9")
    (instances
      (project "kria-k26-devboard"
        (path ""
          (reference "U3") (unit 1)
        )
      )
    )
  )

  (symbol (lib_id "kria-k26-devboard:C_10u_0402") (at 236.22 212.09 90) (mirror x) (unit 1)
    (in_bom yes) (on_board yes) (dnp no)
    (property "Reference" "C249" (at 235.585 212.725 90)
      (effects (font (size 1.524 1.524)) (justify left))
    )
    (property "Value" "C_10u_0402" (at 246.38 232.41 0)
      (effects (font (size 1.27 1.27) (thickness 0.15)) (justify left bottom) hide)
    )
    (property "Footprint" "kria-k26-devboard-footprints:C_0402_1005Metric" (at 248.92 232.41 0)
      (effects (font (size 1.27 1.27) (thickness 0.15)) (justify left bottom) hide)
    )
    (property "Datasheet" " " (at 251.46 232.41 0)
      (effects (font (size 1.27 1.27) (thickness 0.15)) (justify left bottom) hide)
    )
    (property "Manufacturer" "Yaego" (at 256.54 232.41 0)
      (effects (font (size 1.27 1.27) (thickness 0.15)) (justify left bottom) hide)
    )
    (property "MPN" "CC0402MRX5R5BB106" (at 254 232.41 0)
      (effects (font (size 1.27 1.27) (thickness 0.15)) (justify left bottom) hide)
    )
    (property "Val" "10u" (at 235.585 216.535 90)
      (effects (font (size 1.27 1.27) (thickness 0.15)) (justify left))
    )
    (property "License" "Apache-2.0" (at 259.08 232.41 0)
      (effects (font (size 1.27 1.27) (thickness 0.15)) (justify left bottom) hide)
    )
    (property "Author" "Antmicro" (at 261.62 232.41 0)
      (effects (font (size 1.27 1.27) (thickness 0.15)) (justify left bottom) hide)
    )
    (property "Voltage" "" (at 264.16 232.41 0)
      (effects (font (size 1.27 1.27)) (justify left bottom) hide)
    )
    (property "Dielectric" "" (at 266.7 232.41 0)
      (effects (font (size 1.27 1.27)) (justify left bottom) hide)
    )
    (pin "1")
    (pin "2")
    (instances
      (project "kria-k26-devboard"
        (path ""
          (reference "C249") (unit 1)
        )
      )
    )
  )

  (symbol (lib_id "kria-k26-devboard:GND") (at 236.22 217.17 0) (mirror y) (unit 1)
    (in_bom yes) (on_board yes) (dnp no) (fields_autoplaced)
    (property "Reference" "#PWR0327" (at 236.22 223.52 0)
      (effects (font (size 1.27 1.27)) hide)
    )
    (property "Value" "GND" (at 236.22 221.615 0)
      (effects (font (size 1.27 1.27)))
    )
    (property "Footprint" "" (at 227.33 224.79 0)
      (effects (font (size 1.27 1.27) (thickness 0.15)) (justify left bottom) hide)
    )
    (property "Datasheet" "" (at 227.33 229.87 0)
      (effects (font (size 1.27 1.27) (thickness 0.15)) (justify left bottom) hide)
    )
    (property "Author" "Antmicro" (at 227.33 224.79 0)
      (effects (font (size 1.27 1.27) (thickness 0.15)) (justify left bottom) hide)
    )
    (property "License" "Apache-2.0" (at 227.33 227.33 0)
      (effects (font (size 1.27 1.27) (thickness 0.15)) (justify left bottom) hide)
    )
    (pin "1")
    (instances
      (project "kria-k26-devboard"
        (path ""
          (reference "#PWR0327") (unit 1)
        )
      )
    )
  )

  (symbol (lib_id "kria-k26-devboard:GND") (at 244.475 217.17 0) (mirror y) (unit 1)
    (in_bom yes) (on_board yes) (dnp no) (fields_autoplaced)
    (property "Reference" "#PWR0411" (at 244.475 223.52 0)
      (effects (font (size 1.27 1.27)) hide)
    )
    (property "Value" "GND" (at 244.475 221.615 0)
      (effects (font (size 1.27 1.27)))
    )
    (property "Footprint" "" (at 235.585 224.79 0)
      (effects (font (size 1.27 1.27) (thickness 0.15)) (justify left bottom) hide)
    )
    (property "Datasheet" "" (at 235.585 229.87 0)
      (effects (font (size 1.27 1.27) (thickness 0.15)) (justify left bottom) hide)
    )
    (property "Author" "Antmicro" (at 235.585 224.79 0)
      (effects (font (size 1.27 1.27) (thickness 0.15)) (justify left bottom) hide)
    )
    (property "License" "Apache-2.0" (at 235.585 227.33 0)
      (effects (font (size 1.27 1.27) (thickness 0.15)) (justify left bottom) hide)
    )
    (pin "1")
    (instances
      (project "kria-k26-devboard"
        (path ""
          (reference "#PWR0411") (unit 1)
        )
      )
    )
  )
)
